FILE_TYPE = MACRO_DRAWING;
SET COLOR_WIRE YELLOW;
SET COLOR_PROP ORANGE;
SET COLOR_DOT WHITE;
SET COLOR_ARC YELLOW;
SET COLOR_BODY GREEN;
SET COLOR_NOTE PURPLE;
SET PROP_DISPLAY VALUE;
SET PAGE_NUMBER P102;
FORCEADD OFFPAGE..5
(-8425 2125);
FORCEPROP 2 LAST $XR0 42 
J 0
(-8649 2125);
DISPLAY 0.638298 (-8649 2125);
PAINT MONO (-8649 2125);
FORCEPROP 2 LAST CDS_LIB mstr_standard
J 0
(-8425 2125);
DISPLAY 0.808511 (-8425 2125);
DISPLAY INVISIBLE (-8425 2125);
FORCEPROP 1 LAST OFFPAGE TRUE
J 0
(-8100 2000);
DISPLAY 0.872340 (-8100 2000);
PAINT GREEN (-8100 2000);
DISPLAY INVISIBLE (-8100 2000);
FORCEPROP 1 LAST COMMENT_BODY TRUE
J 0
(-8325 2050);
DISPLAY 0.872340 (-8325 2050);
PAINT GREEN (-8325 2050);
DISPLAY INVISIBLE (-8325 2050);
FORCEPROP 2 LAST PATH I1
J 0
(-8625 2175);
DISPLAY 1.021277 (-8625 2175);
DISPLAY INVISIBLE (-8625 2175);
FORCEADD OFFPAGE..6
(-8425 3725);
FORCEPROP 2 LAST $XR0 42 
J 0
(-8674 3725);
DISPLAY 0.638298 (-8674 3725);
PAINT MONO (-8674 3725);
FORCEPROP 2 LAST CDS_LIB mstr_standard
J 0
(-8425 3725);
DISPLAY 0.723404 (-8425 3725);
PAINT MONO (-8425 3725);
DISPLAY INVISIBLE (-8425 3725);
FORCEPROP 1 LAST OFFPAGE TRUE
J 0
(-8100 3600);
DISPLAY 0.872340 (-8100 3600);
PAINT GREEN (-8100 3600);
DISPLAY INVISIBLE (-8100 3600);
FORCEPROP 1 LAST COMMENT_BODY TRUE
J 0
(-8325 3650);
DISPLAY 0.872340 (-8325 3650);
PAINT GREEN (-8325 3650);
DISPLAY INVISIBLE (-8325 3650);
FORCEPROP 2 LAST PATH I10
J 0
(-8650 3775);
DISPLAY 1.021277 (-8650 3775);
DISPLAY INVISIBLE (-8650 3775);
FORCEADD TAP..1
(-6125 4325);
FORCEPROP 3 LASTPIN (-6175 4325) SIG_NAME M_F_CPU1_SA_DQ<7>
J 0
(-6165 4335);
DISPLAY 0.659574 (-6165 4335);
PAINT MONO (-6165 4335);
DISPLAY INVISIBLE (-6165 4335);
FORCEPROP 1 LASTPIN (-6175 4325) BN 7
J 0
(-6187 4333);
DISPLAY 0.489362 (-6187 4333);
PAINT GREEN (-6187 4333);
FORCEPROP 2 LAST CDS_LIB mstr_standard
J 0
(-6125 4325);
DISPLAY 0.723404 (-6125 4325);
PAINT MONO (-6125 4325);
DISPLAY INVISIBLE (-6125 4325);
FORCEPROP 1 LAST BODY_TYPE PLUMBING
J 0
(-6125 4375);
DISPLAY 0.872340 (-6125 4375);
PAINT GREEN (-6125 4375);
DISPLAY INVISIBLE (-6125 4375);
FORCEPROP 1 LAST HDL_TAP TRUE
J 0
(-5800 4200);
DISPLAY 0.872340 (-5800 4200);
DISPLAY INVISIBLE (-5800 4200);
FORCEPROP 1 LAST PATH I100
J 0
(-6127 4325);
DISPLAY 0.872340 (-6127 4325);
PAINT GREEN (-6127 4325);
DISPLAY INVISIBLE (-6127 4325);
FORCEADD TAP..1
(-6125 4275);
FORCEPROP 3 LASTPIN (-6175 4275) SIG_NAME M_F_CPU1_SA_DQ<6>
J 0
(-6165 4285);
DISPLAY 0.659574 (-6165 4285);
PAINT MONO (-6165 4285);
DISPLAY INVISIBLE (-6165 4285);
FORCEPROP 1 LASTPIN (-6175 4275) BN 6
J 0
(-6187 4283);
DISPLAY 0.489362 (-6187 4283);
PAINT GREEN (-6187 4283);
FORCEPROP 2 LAST CDS_LIB mstr_standard
J 0
(-6125 4275);
DISPLAY 0.723404 (-6125 4275);
PAINT MONO (-6125 4275);
DISPLAY INVISIBLE (-6125 4275);
FORCEPROP 1 LAST BODY_TYPE PLUMBING
J 0
(-6125 4325);
DISPLAY 0.872340 (-6125 4325);
PAINT GREEN (-6125 4325);
DISPLAY INVISIBLE (-6125 4325);
FORCEPROP 1 LAST HDL_TAP TRUE
J 0
(-5800 4150);
DISPLAY 0.872340 (-5800 4150);
DISPLAY INVISIBLE (-5800 4150);
FORCEPROP 1 LAST PATH I101
J 0
(-6127 4275);
DISPLAY 0.872340 (-6127 4275);
PAINT GREEN (-6127 4275);
DISPLAY INVISIBLE (-6127 4275);
FORCEADD TAP..1
(-6125 4375);
FORCEPROP 3 LASTPIN (-6175 4375) SIG_NAME M_F_CPU1_SA_DQ<8>
J 0
(-6165 4385);
DISPLAY 0.659574 (-6165 4385);
PAINT MONO (-6165 4385);
DISPLAY INVISIBLE (-6165 4385);
FORCEPROP 1 LASTPIN (-6175 4375) BN 8
J 0
(-6187 4383);
DISPLAY 0.489362 (-6187 4383);
PAINT GREEN (-6187 4383);
FORCEPROP 2 LAST CDS_LIB mstr_standard
J 0
(-6125 4375);
DISPLAY 0.723404 (-6125 4375);
PAINT MONO (-6125 4375);
DISPLAY INVISIBLE (-6125 4375);
FORCEPROP 1 LAST BODY_TYPE PLUMBING
J 0
(-6125 4425);
DISPLAY 0.872340 (-6125 4425);
PAINT GREEN (-6125 4425);
DISPLAY INVISIBLE (-6125 4425);
FORCEPROP 1 LAST HDL_TAP TRUE
J 0
(-5800 4250);
DISPLAY 0.872340 (-5800 4250);
DISPLAY INVISIBLE (-5800 4250);
FORCEPROP 1 LAST PATH I102
J 0
(-6127 4375);
DISPLAY 0.872340 (-6127 4375);
PAINT GREEN (-6127 4375);
DISPLAY INVISIBLE (-6127 4375);
FORCEADD TAP..1
(-6125 4425);
FORCEPROP 3 LASTPIN (-6175 4425) SIG_NAME M_F_CPU1_SA_DQ<9>
J 0
(-6165 4435);
DISPLAY 0.659574 (-6165 4435);
PAINT MONO (-6165 4435);
DISPLAY INVISIBLE (-6165 4435);
FORCEPROP 1 LASTPIN (-6175 4425) BN 9
J 0
(-6187 4433);
DISPLAY 0.489362 (-6187 4433);
PAINT GREEN (-6187 4433);
FORCEPROP 2 LAST CDS_LIB mstr_standard
J 0
(-6125 4425);
DISPLAY 0.723404 (-6125 4425);
PAINT MONO (-6125 4425);
DISPLAY INVISIBLE (-6125 4425);
FORCEPROP 1 LAST BODY_TYPE PLUMBING
J 0
(-6125 4475);
DISPLAY 0.872340 (-6125 4475);
PAINT GREEN (-6125 4475);
DISPLAY INVISIBLE (-6125 4475);
FORCEPROP 1 LAST HDL_TAP TRUE
J 0
(-5800 4300);
DISPLAY 0.872340 (-5800 4300);
DISPLAY INVISIBLE (-5800 4300);
FORCEPROP 1 LAST PATH I103
J 0
(-6127 4425);
DISPLAY 0.872340 (-6127 4425);
PAINT GREEN (-6127 4425);
DISPLAY INVISIBLE (-6127 4425);
FORCEADD TAP..1
(-6125 4525);
FORCEPROP 3 LASTPIN (-6175 4525) SIG_NAME M_F_CPU1_SA_DQ<11>
J 0
(-6165 4535);
DISPLAY 0.659574 (-6165 4535);
PAINT MONO (-6165 4535);
DISPLAY INVISIBLE (-6165 4535);
FORCEPROP 1 LASTPIN (-6175 4525) BN 11
J 0
(-6187 4533);
DISPLAY 0.489362 (-6187 4533);
PAINT GREEN (-6187 4533);
FORCEPROP 2 LAST CDS_LIB mstr_standard
J 0
(-6125 4525);
DISPLAY 0.723404 (-6125 4525);
PAINT MONO (-6125 4525);
DISPLAY INVISIBLE (-6125 4525);
FORCEPROP 1 LAST BODY_TYPE PLUMBING
J 0
(-6125 4575);
DISPLAY 0.872340 (-6125 4575);
PAINT GREEN (-6125 4575);
DISPLAY INVISIBLE (-6125 4575);
FORCEPROP 1 LAST HDL_TAP TRUE
J 0
(-5800 4400);
DISPLAY 0.872340 (-5800 4400);
DISPLAY INVISIBLE (-5800 4400);
FORCEPROP 1 LAST PATH I104
J 0
(-6127 4525);
DISPLAY 0.872340 (-6127 4525);
PAINT GREEN (-6127 4525);
DISPLAY INVISIBLE (-6127 4525);
FORCEADD TAP..1
(-6125 4575);
FORCEPROP 3 LASTPIN (-6175 4575) SIG_NAME M_F_CPU1_SA_DQ<12>
J 0
(-6165 4585);
DISPLAY 0.659574 (-6165 4585);
PAINT MONO (-6165 4585);
DISPLAY INVISIBLE (-6165 4585);
FORCEPROP 1 LASTPIN (-6175 4575) BN 12
J 0
(-6187 4583);
DISPLAY 0.489362 (-6187 4583);
PAINT GREEN (-6187 4583);
FORCEPROP 2 LAST CDS_LIB mstr_standard
J 0
(-6125 4575);
DISPLAY 0.723404 (-6125 4575);
PAINT MONO (-6125 4575);
DISPLAY INVISIBLE (-6125 4575);
FORCEPROP 1 LAST BODY_TYPE PLUMBING
J 0
(-6125 4625);
DISPLAY 0.872340 (-6125 4625);
PAINT GREEN (-6125 4625);
DISPLAY INVISIBLE (-6125 4625);
FORCEPROP 1 LAST HDL_TAP TRUE
J 0
(-5800 4450);
DISPLAY 0.872340 (-5800 4450);
DISPLAY INVISIBLE (-5800 4450);
FORCEPROP 1 LAST PATH I105
J 0
(-6127 4575);
DISPLAY 0.872340 (-6127 4575);
PAINT GREEN (-6127 4575);
DISPLAY INVISIBLE (-6127 4575);
FORCEADD TAP..1
(-6125 4625);
FORCEPROP 3 LASTPIN (-6175 4625) SIG_NAME M_F_CPU1_SA_DQ<13>
J 0
(-6165 4635);
DISPLAY 0.659574 (-6165 4635);
PAINT MONO (-6165 4635);
DISPLAY INVISIBLE (-6165 4635);
FORCEPROP 1 LASTPIN (-6175 4625) BN 13
J 0
(-6187 4633);
DISPLAY 0.489362 (-6187 4633);
PAINT GREEN (-6187 4633);
FORCEPROP 2 LAST CDS_LIB mstr_standard
J 0
(-6125 4625);
DISPLAY 0.723404 (-6125 4625);
PAINT MONO (-6125 4625);
DISPLAY INVISIBLE (-6125 4625);
FORCEPROP 1 LAST BODY_TYPE PLUMBING
J 0
(-6125 4675);
DISPLAY 0.872340 (-6125 4675);
PAINT GREEN (-6125 4675);
DISPLAY INVISIBLE (-6125 4675);
FORCEPROP 1 LAST HDL_TAP TRUE
J 0
(-5800 4500);
DISPLAY 0.872340 (-5800 4500);
DISPLAY INVISIBLE (-5800 4500);
FORCEPROP 1 LAST PATH I106
J 0
(-6127 4625);
DISPLAY 0.872340 (-6127 4625);
PAINT GREEN (-6127 4625);
DISPLAY INVISIBLE (-6127 4625);
FORCEADD TAP..1
(-6125 4675);
FORCEPROP 3 LASTPIN (-6175 4675) SIG_NAME M_F_CPU1_SA_DQ<14>
J 0
(-6165 4685);
DISPLAY 0.659574 (-6165 4685);
PAINT MONO (-6165 4685);
DISPLAY INVISIBLE (-6165 4685);
FORCEPROP 1 LASTPIN (-6175 4675) BN 14
J 0
(-6187 4683);
DISPLAY 0.489362 (-6187 4683);
PAINT GREEN (-6187 4683);
FORCEPROP 2 LAST CDS_LIB mstr_standard
J 0
(-6125 4675);
DISPLAY 0.723404 (-6125 4675);
PAINT MONO (-6125 4675);
DISPLAY INVISIBLE (-6125 4675);
FORCEPROP 1 LAST BODY_TYPE PLUMBING
J 0
(-6125 4725);
DISPLAY 0.872340 (-6125 4725);
PAINT GREEN (-6125 4725);
DISPLAY INVISIBLE (-6125 4725);
FORCEPROP 1 LAST HDL_TAP TRUE
J 0
(-5800 4550);
DISPLAY 0.872340 (-5800 4550);
DISPLAY INVISIBLE (-5800 4550);
FORCEPROP 1 LAST PATH I107
J 0
(-6127 4675);
DISPLAY 0.872340 (-6127 4675);
PAINT GREEN (-6127 4675);
DISPLAY INVISIBLE (-6127 4675);
FORCEADD TAP..1
(-6125 4475);
FORCEPROP 3 LASTPIN (-6175 4475) SIG_NAME M_F_CPU1_SA_DQ<10>
J 0
(-6165 4485);
DISPLAY 0.659574 (-6165 4485);
PAINT MONO (-6165 4485);
DISPLAY INVISIBLE (-6165 4485);
FORCEPROP 1 LASTPIN (-6175 4475) BN 10
J 0
(-6187 4483);
DISPLAY 0.489362 (-6187 4483);
PAINT GREEN (-6187 4483);
FORCEPROP 2 LAST CDS_LIB mstr_standard
J 0
(-6125 4475);
DISPLAY 0.723404 (-6125 4475);
PAINT MONO (-6125 4475);
DISPLAY INVISIBLE (-6125 4475);
FORCEPROP 1 LAST BODY_TYPE PLUMBING
J 0
(-6125 4525);
DISPLAY 0.872340 (-6125 4525);
PAINT GREEN (-6125 4525);
DISPLAY INVISIBLE (-6125 4525);
FORCEPROP 1 LAST HDL_TAP TRUE
J 0
(-5800 4350);
DISPLAY 0.872340 (-5800 4350);
DISPLAY INVISIBLE (-5800 4350);
FORCEPROP 1 LAST PATH I108
J 0
(-6127 4475);
DISPLAY 0.872340 (-6127 4475);
PAINT GREEN (-6127 4475);
DISPLAY INVISIBLE (-6127 4475);
FORCEADD TAP..1
(-6125 4925);
FORCEPROP 3 LASTPIN (-6175 4925) SIG_NAME M_F_CPU1_SA_DQ<19>
J 0
(-6165 4935);
DISPLAY 0.659574 (-6165 4935);
PAINT MONO (-6165 4935);
DISPLAY INVISIBLE (-6165 4935);
FORCEPROP 1 LASTPIN (-6175 4925) BN 19
J 0
(-6187 4933);
DISPLAY 0.489362 (-6187 4933);
PAINT GREEN (-6187 4933);
FORCEPROP 2 LAST CDS_LIB mstr_standard
J 0
(-6125 4925);
DISPLAY 0.723404 (-6125 4925);
PAINT MONO (-6125 4925);
DISPLAY INVISIBLE (-6125 4925);
FORCEPROP 1 LAST BODY_TYPE PLUMBING
J 0
(-6125 4975);
DISPLAY 0.872340 (-6125 4975);
PAINT GREEN (-6125 4975);
DISPLAY INVISIBLE (-6125 4975);
FORCEPROP 1 LAST HDL_TAP TRUE
J 0
(-5800 4800);
DISPLAY 0.872340 (-5800 4800);
DISPLAY INVISIBLE (-5800 4800);
FORCEPROP 1 LAST PATH I109
J 0
(-6127 4925);
DISPLAY 0.872340 (-6127 4925);
PAINT GREEN (-6127 4925);
DISPLAY INVISIBLE (-6127 4925);
FORCEADD OFFPAGE..6
(-8425 4175);
FORCEPROP 2 LAST $XR0 42 
J 0
(-8674 4175);
DISPLAY 0.638298 (-8674 4175);
PAINT MONO (-8674 4175);
FORCEPROP 2 LAST CDS_LIB mstr_standard
J 0
(-8425 4175);
DISPLAY 0.723404 (-8425 4175);
PAINT MONO (-8425 4175);
DISPLAY INVISIBLE (-8425 4175);
FORCEPROP 1 LAST OFFPAGE TRUE
J 0
(-8100 4050);
DISPLAY 0.872340 (-8100 4050);
PAINT GREEN (-8100 4050);
DISPLAY INVISIBLE (-8100 4050);
FORCEPROP 1 LAST COMMENT_BODY TRUE
J 0
(-8325 4100);
DISPLAY 0.872340 (-8325 4100);
PAINT GREEN (-8325 4100);
DISPLAY INVISIBLE (-8325 4100);
FORCEPROP 2 LAST PATH I11
J 0
(-8650 4225);
DISPLAY 1.021277 (-8650 4225);
DISPLAY INVISIBLE (-8650 4225);
FORCEADD TAP..1
(-6125 4775);
FORCEPROP 3 LASTPIN (-6175 4775) SIG_NAME M_F_CPU1_SA_DQ<16>
J 0
(-6165 4785);
DISPLAY 0.659574 (-6165 4785);
PAINT MONO (-6165 4785);
DISPLAY INVISIBLE (-6165 4785);
FORCEPROP 1 LASTPIN (-6175 4775) BN 16
J 0
(-6187 4783);
DISPLAY 0.489362 (-6187 4783);
PAINT GREEN (-6187 4783);
FORCEPROP 2 LAST CDS_LIB mstr_standard
J 0
(-6125 4775);
DISPLAY 0.723404 (-6125 4775);
PAINT MONO (-6125 4775);
DISPLAY INVISIBLE (-6125 4775);
FORCEPROP 1 LAST BODY_TYPE PLUMBING
J 0
(-6125 4825);
DISPLAY 0.872340 (-6125 4825);
PAINT GREEN (-6125 4825);
DISPLAY INVISIBLE (-6125 4825);
FORCEPROP 1 LAST HDL_TAP TRUE
J 0
(-5800 4650);
DISPLAY 0.872340 (-5800 4650);
DISPLAY INVISIBLE (-5800 4650);
FORCEPROP 1 LAST PATH I110
J 0
(-6127 4775);
DISPLAY 0.872340 (-6127 4775);
PAINT GREEN (-6127 4775);
DISPLAY INVISIBLE (-6127 4775);
FORCEADD TAP..1
(-6125 4875);
FORCEPROP 3 LASTPIN (-6175 4875) SIG_NAME M_F_CPU1_SA_DQ<18>
J 0
(-6165 4885);
DISPLAY 0.659574 (-6165 4885);
PAINT MONO (-6165 4885);
DISPLAY INVISIBLE (-6165 4885);
FORCEPROP 1 LASTPIN (-6175 4875) BN 18
J 0
(-6187 4883);
DISPLAY 0.489362 (-6187 4883);
PAINT GREEN (-6187 4883);
FORCEPROP 2 LAST CDS_LIB mstr_standard
J 0
(-6125 4875);
DISPLAY 0.723404 (-6125 4875);
PAINT MONO (-6125 4875);
DISPLAY INVISIBLE (-6125 4875);
FORCEPROP 1 LAST BODY_TYPE PLUMBING
J 0
(-6125 4925);
DISPLAY 0.872340 (-6125 4925);
PAINT GREEN (-6125 4925);
DISPLAY INVISIBLE (-6125 4925);
FORCEPROP 1 LAST HDL_TAP TRUE
J 0
(-5800 4750);
DISPLAY 0.872340 (-5800 4750);
DISPLAY INVISIBLE (-5800 4750);
FORCEPROP 1 LAST PATH I111
J 0
(-6127 4875);
DISPLAY 0.872340 (-6127 4875);
PAINT GREEN (-6127 4875);
DISPLAY INVISIBLE (-6127 4875);
FORCEADD TAP..1
(-6125 4825);
FORCEPROP 3 LASTPIN (-6175 4825) SIG_NAME M_F_CPU1_SA_DQ<17>
J 0
(-6165 4835);
DISPLAY 0.659574 (-6165 4835);
PAINT MONO (-6165 4835);
DISPLAY INVISIBLE (-6165 4835);
FORCEPROP 1 LASTPIN (-6175 4825) BN 17
J 0
(-6187 4833);
DISPLAY 0.489362 (-6187 4833);
PAINT GREEN (-6187 4833);
FORCEPROP 2 LAST CDS_LIB mstr_standard
J 0
(-6125 4825);
DISPLAY 0.723404 (-6125 4825);
PAINT MONO (-6125 4825);
DISPLAY INVISIBLE (-6125 4825);
FORCEPROP 1 LAST BODY_TYPE PLUMBING
J 0
(-6125 4875);
DISPLAY 0.872340 (-6125 4875);
PAINT GREEN (-6125 4875);
DISPLAY INVISIBLE (-6125 4875);
FORCEPROP 1 LAST HDL_TAP TRUE
J 0
(-5800 4700);
DISPLAY 0.872340 (-5800 4700);
DISPLAY INVISIBLE (-5800 4700);
FORCEPROP 1 LAST PATH I112
J 0
(-6127 4825);
DISPLAY 0.872340 (-6127 4825);
PAINT GREEN (-6127 4825);
DISPLAY INVISIBLE (-6127 4825);
FORCEADD TAP..1
(-6125 4725);
FORCEPROP 3 LASTPIN (-6175 4725) SIG_NAME M_F_CPU1_SA_DQ<15>
J 0
(-6165 4735);
DISPLAY 0.659574 (-6165 4735);
PAINT MONO (-6165 4735);
DISPLAY INVISIBLE (-6165 4735);
FORCEPROP 1 LASTPIN (-6175 4725) BN 15
J 0
(-6187 4733);
DISPLAY 0.489362 (-6187 4733);
PAINT GREEN (-6187 4733);
FORCEPROP 2 LAST CDS_LIB mstr_standard
J 0
(-6125 4725);
DISPLAY 0.723404 (-6125 4725);
PAINT MONO (-6125 4725);
DISPLAY INVISIBLE (-6125 4725);
FORCEPROP 1 LAST BODY_TYPE PLUMBING
J 0
(-6125 4775);
DISPLAY 0.872340 (-6125 4775);
PAINT GREEN (-6125 4775);
DISPLAY INVISIBLE (-6125 4775);
FORCEPROP 1 LAST HDL_TAP TRUE
J 0
(-5800 4600);
DISPLAY 0.872340 (-5800 4600);
DISPLAY INVISIBLE (-5800 4600);
FORCEPROP 1 LAST PATH I113
J 0
(-6127 4725);
DISPLAY 0.872340 (-6127 4725);
PAINT GREEN (-6127 4725);
DISPLAY INVISIBLE (-6127 4725);
FORCEADD TAP..1
(-6125 4975);
FORCEPROP 3 LASTPIN (-6175 4975) SIG_NAME M_F_CPU1_SA_DQ<20>
J 0
(-6165 4985);
DISPLAY 0.659574 (-6165 4985);
PAINT MONO (-6165 4985);
DISPLAY INVISIBLE (-6165 4985);
FORCEPROP 1 LASTPIN (-6175 4975) BN 20
J 0
(-6187 4983);
DISPLAY 0.489362 (-6187 4983);
PAINT GREEN (-6187 4983);
FORCEPROP 2 LAST CDS_LIB mstr_standard
J 0
(-6125 4975);
DISPLAY 0.723404 (-6125 4975);
PAINT MONO (-6125 4975);
DISPLAY INVISIBLE (-6125 4975);
FORCEPROP 1 LAST BODY_TYPE PLUMBING
J 0
(-6125 5025);
DISPLAY 0.872340 (-6125 5025);
PAINT GREEN (-6125 5025);
DISPLAY INVISIBLE (-6125 5025);
FORCEPROP 1 LAST HDL_TAP TRUE
J 0
(-5800 4850);
DISPLAY 0.872340 (-5800 4850);
DISPLAY INVISIBLE (-5800 4850);
FORCEPROP 1 LAST PATH I114
J 0
(-6127 4975);
DISPLAY 0.872340 (-6127 4975);
PAINT GREEN (-6127 4975);
DISPLAY INVISIBLE (-6127 4975);
FORCEADD TAP..1
(-6125 5025);
FORCEPROP 3 LASTPIN (-6175 5025) SIG_NAME M_F_CPU1_SA_DQ<21>
J 0
(-6165 5035);
DISPLAY 0.659574 (-6165 5035);
PAINT MONO (-6165 5035);
DISPLAY INVISIBLE (-6165 5035);
FORCEPROP 1 LASTPIN (-6175 5025) BN 21
J 0
(-6187 5033);
DISPLAY 0.489362 (-6187 5033);
PAINT GREEN (-6187 5033);
FORCEPROP 2 LAST CDS_LIB mstr_standard
J 0
(-6125 5025);
DISPLAY 0.723404 (-6125 5025);
PAINT MONO (-6125 5025);
DISPLAY INVISIBLE (-6125 5025);
FORCEPROP 1 LAST BODY_TYPE PLUMBING
J 0
(-6125 5075);
DISPLAY 0.872340 (-6125 5075);
PAINT GREEN (-6125 5075);
DISPLAY INVISIBLE (-6125 5075);
FORCEPROP 1 LAST HDL_TAP TRUE
J 0
(-5800 4900);
DISPLAY 0.872340 (-5800 4900);
DISPLAY INVISIBLE (-5800 4900);
FORCEPROP 1 LAST PATH I115
J 0
(-6127 5025);
DISPLAY 0.872340 (-6127 5025);
PAINT GREEN (-6127 5025);
DISPLAY INVISIBLE (-6127 5025);
FORCEADD TAP..1
(-6125 5075);
FORCEPROP 3 LASTPIN (-6175 5075) SIG_NAME M_F_CPU1_SA_DQ<22>
J 0
(-6165 5085);
DISPLAY 0.659574 (-6165 5085);
PAINT MONO (-6165 5085);
DISPLAY INVISIBLE (-6165 5085);
FORCEPROP 1 LASTPIN (-6175 5075) BN 22
J 0
(-6187 5083);
DISPLAY 0.489362 (-6187 5083);
PAINT GREEN (-6187 5083);
FORCEPROP 2 LAST CDS_LIB mstr_standard
J 0
(-6125 5075);
DISPLAY 0.723404 (-6125 5075);
PAINT MONO (-6125 5075);
DISPLAY INVISIBLE (-6125 5075);
FORCEPROP 1 LAST BODY_TYPE PLUMBING
J 0
(-6125 5125);
DISPLAY 0.872340 (-6125 5125);
PAINT GREEN (-6125 5125);
DISPLAY INVISIBLE (-6125 5125);
FORCEPROP 1 LAST HDL_TAP TRUE
J 0
(-5800 4950);
DISPLAY 0.872340 (-5800 4950);
DISPLAY INVISIBLE (-5800 4950);
FORCEPROP 1 LAST PATH I116
J 0
(-6127 5075);
DISPLAY 0.872340 (-6127 5075);
PAINT GREEN (-6127 5075);
DISPLAY INVISIBLE (-6127 5075);
FORCEADD TAP..1
(-6125 5225);
FORCEPROP 3 LASTPIN (-6175 5225) SIG_NAME M_F_CPU1_SA_DQ<25>
J 0
(-6165 5235);
DISPLAY 0.659574 (-6165 5235);
PAINT MONO (-6165 5235);
DISPLAY INVISIBLE (-6165 5235);
FORCEPROP 1 LASTPIN (-6175 5225) BN 25
J 0
(-6187 5233);
DISPLAY 0.489362 (-6187 5233);
PAINT GREEN (-6187 5233);
FORCEPROP 2 LAST CDS_LIB mstr_standard
J 0
(-6125 5225);
DISPLAY 0.723404 (-6125 5225);
PAINT MONO (-6125 5225);
DISPLAY INVISIBLE (-6125 5225);
FORCEPROP 1 LAST BODY_TYPE PLUMBING
J 0
(-6125 5275);
DISPLAY 0.872340 (-6125 5275);
PAINT GREEN (-6125 5275);
DISPLAY INVISIBLE (-6125 5275);
FORCEPROP 1 LAST HDL_TAP TRUE
J 0
(-5800 5100);
DISPLAY 0.872340 (-5800 5100);
DISPLAY INVISIBLE (-5800 5100);
FORCEPROP 1 LAST PATH I117
J 0
(-6127 5225);
DISPLAY 0.872340 (-6127 5225);
PAINT GREEN (-6127 5225);
DISPLAY INVISIBLE (-6127 5225);
FORCEADD TAP..1
(-6125 5125);
FORCEPROP 3 LASTPIN (-6175 5125) SIG_NAME M_F_CPU1_SA_DQ<23>
J 0
(-6165 5135);
DISPLAY 0.659574 (-6165 5135);
PAINT MONO (-6165 5135);
DISPLAY INVISIBLE (-6165 5135);
FORCEPROP 1 LASTPIN (-6175 5125) BN 23
J 0
(-6187 5133);
DISPLAY 0.489362 (-6187 5133);
PAINT GREEN (-6187 5133);
FORCEPROP 2 LAST CDS_LIB mstr_standard
J 0
(-6125 5125);
DISPLAY 0.723404 (-6125 5125);
PAINT MONO (-6125 5125);
DISPLAY INVISIBLE (-6125 5125);
FORCEPROP 1 LAST BODY_TYPE PLUMBING
J 0
(-6125 5175);
DISPLAY 0.872340 (-6125 5175);
PAINT GREEN (-6125 5175);
DISPLAY INVISIBLE (-6125 5175);
FORCEPROP 1 LAST HDL_TAP TRUE
J 0
(-5800 5000);
DISPLAY 0.872340 (-5800 5000);
DISPLAY INVISIBLE (-5800 5000);
FORCEPROP 1 LAST PATH I118
J 0
(-6127 5125);
DISPLAY 0.872340 (-6127 5125);
PAINT GREEN (-6127 5125);
DISPLAY INVISIBLE (-6127 5125);
FORCEADD TAP..1
(-6125 5175);
FORCEPROP 3 LASTPIN (-6175 5175) SIG_NAME M_F_CPU1_SA_DQ<24>
J 0
(-6165 5185);
DISPLAY 0.659574 (-6165 5185);
PAINT MONO (-6165 5185);
DISPLAY INVISIBLE (-6165 5185);
FORCEPROP 1 LASTPIN (-6175 5175) BN 24
J 0
(-6187 5183);
DISPLAY 0.489362 (-6187 5183);
PAINT GREEN (-6187 5183);
FORCEPROP 2 LAST CDS_LIB mstr_standard
J 0
(-6125 5175);
DISPLAY 0.723404 (-6125 5175);
PAINT MONO (-6125 5175);
DISPLAY INVISIBLE (-6125 5175);
FORCEPROP 1 LAST BODY_TYPE PLUMBING
J 0
(-6125 5225);
DISPLAY 0.872340 (-6125 5225);
PAINT GREEN (-6125 5225);
DISPLAY INVISIBLE (-6125 5225);
FORCEPROP 1 LAST HDL_TAP TRUE
J 0
(-5800 5050);
DISPLAY 0.872340 (-5800 5050);
DISPLAY INVISIBLE (-5800 5050);
FORCEPROP 1 LAST PATH I119
J 0
(-6127 5175);
DISPLAY 0.872340 (-6127 5175);
PAINT GREEN (-6127 5175);
DISPLAY INVISIBLE (-6127 5175);
FORCEADD OFFPAGE..1
(-8425 4225);
FORCEPROP 2 LAST $XR0 42 
J 0
(-8646 4225);
DISPLAY 0.638298 (-8646 4225);
PAINT MONO (-8646 4225);
FORCEPROP 2 LAST CDS_LIB mstr_standard
J 0
(-8425 4225);
DISPLAY 0.808511 (-8425 4225);
DISPLAY INVISIBLE (-8425 4225);
FORCEPROP 1 LAST OFFPAGE TRUE
J 0
(-8100 4100);
DISPLAY 0.872340 (-8100 4100);
PAINT GREEN (-8100 4100);
DISPLAY INVISIBLE (-8100 4100);
FORCEPROP 1 LAST COMMENT_BODY TRUE
J 0
(-8300 4125);
DISPLAY 0.872340 (-8300 4125);
PAINT GREEN (-8300 4125);
DISPLAY INVISIBLE (-8300 4125);
FORCEPROP 2 LAST PATH I12
J 0
(-8675 4275);
DISPLAY 1.021277 (-8675 4275);
DISPLAY INVISIBLE (-8675 4275);
FORCEADD TAP..1
(-6125 5425);
FORCEPROP 3 LASTPIN (-6175 5425) SIG_NAME M_F_CPU1_SA_DQ<29>
J 0
(-6165 5435);
DISPLAY 0.659574 (-6165 5435);
PAINT MONO (-6165 5435);
DISPLAY INVISIBLE (-6165 5435);
FORCEPROP 1 LASTPIN (-6175 5425) BN 29
J 0
(-6187 5433);
DISPLAY 0.489362 (-6187 5433);
PAINT GREEN (-6187 5433);
FORCEPROP 2 LAST CDS_LIB mstr_standard
J 0
(-6125 5425);
DISPLAY 0.723404 (-6125 5425);
PAINT MONO (-6125 5425);
DISPLAY INVISIBLE (-6125 5425);
FORCEPROP 1 LAST BODY_TYPE PLUMBING
J 0
(-6125 5475);
DISPLAY 0.872340 (-6125 5475);
PAINT GREEN (-6125 5475);
DISPLAY INVISIBLE (-6125 5475);
FORCEPROP 1 LAST HDL_TAP TRUE
J 0
(-5800 5300);
DISPLAY 0.872340 (-5800 5300);
DISPLAY INVISIBLE (-5800 5300);
FORCEPROP 1 LAST PATH I120
J 0
(-6127 5425);
DISPLAY 0.872340 (-6127 5425);
PAINT GREEN (-6127 5425);
DISPLAY INVISIBLE (-6127 5425);
FORCEADD TAP..1
(-6125 5475);
FORCEPROP 3 LASTPIN (-6175 5475) SIG_NAME M_F_CPU1_SA_DQ<30>
J 0
(-6165 5485);
DISPLAY 0.659574 (-6165 5485);
PAINT MONO (-6165 5485);
DISPLAY INVISIBLE (-6165 5485);
FORCEPROP 1 LASTPIN (-6175 5475) BN 30
J 0
(-6187 5483);
DISPLAY 0.489362 (-6187 5483);
PAINT GREEN (-6187 5483);
FORCEPROP 2 LAST CDS_LIB mstr_standard
J 0
(-6125 5475);
DISPLAY 0.723404 (-6125 5475);
PAINT MONO (-6125 5475);
DISPLAY INVISIBLE (-6125 5475);
FORCEPROP 1 LAST BODY_TYPE PLUMBING
J 0
(-6125 5525);
DISPLAY 0.872340 (-6125 5525);
PAINT GREEN (-6125 5525);
DISPLAY INVISIBLE (-6125 5525);
FORCEPROP 1 LAST HDL_TAP TRUE
J 0
(-5800 5350);
DISPLAY 0.872340 (-5800 5350);
DISPLAY INVISIBLE (-5800 5350);
FORCEPROP 1 LAST PATH I121
J 0
(-6127 5475);
DISPLAY 0.872340 (-6127 5475);
PAINT GREEN (-6127 5475);
DISPLAY INVISIBLE (-6127 5475);
FORCEADD TAP..1
(-6125 5375);
FORCEPROP 3 LASTPIN (-6175 5375) SIG_NAME M_F_CPU1_SA_DQ<28>
J 0
(-6165 5385);
DISPLAY 0.659574 (-6165 5385);
PAINT MONO (-6165 5385);
DISPLAY INVISIBLE (-6165 5385);
FORCEPROP 1 LASTPIN (-6175 5375) BN 28
J 0
(-6187 5383);
DISPLAY 0.489362 (-6187 5383);
PAINT GREEN (-6187 5383);
FORCEPROP 2 LAST CDS_LIB mstr_standard
J 0
(-6125 5375);
DISPLAY 0.723404 (-6125 5375);
PAINT MONO (-6125 5375);
DISPLAY INVISIBLE (-6125 5375);
FORCEPROP 1 LAST BODY_TYPE PLUMBING
J 0
(-6125 5425);
DISPLAY 0.872340 (-6125 5425);
PAINT GREEN (-6125 5425);
DISPLAY INVISIBLE (-6125 5425);
FORCEPROP 1 LAST HDL_TAP TRUE
J 0
(-5800 5250);
DISPLAY 0.872340 (-5800 5250);
DISPLAY INVISIBLE (-5800 5250);
FORCEPROP 1 LAST PATH I122
J 0
(-6127 5375);
DISPLAY 0.872340 (-6127 5375);
PAINT GREEN (-6127 5375);
DISPLAY INVISIBLE (-6127 5375);
FORCEADD TAP..1
(-6125 5325);
FORCEPROP 3 LASTPIN (-6175 5325) SIG_NAME M_F_CPU1_SA_DQ<27>
J 0
(-6165 5335);
DISPLAY 0.659574 (-6165 5335);
PAINT MONO (-6165 5335);
DISPLAY INVISIBLE (-6165 5335);
FORCEPROP 1 LASTPIN (-6175 5325) BN 27
J 0
(-6187 5333);
DISPLAY 0.489362 (-6187 5333);
PAINT GREEN (-6187 5333);
FORCEPROP 2 LAST CDS_LIB mstr_standard
J 0
(-6125 5325);
DISPLAY 0.723404 (-6125 5325);
PAINT MONO (-6125 5325);
DISPLAY INVISIBLE (-6125 5325);
FORCEPROP 1 LAST BODY_TYPE PLUMBING
J 0
(-6125 5375);
DISPLAY 0.872340 (-6125 5375);
PAINT GREEN (-6125 5375);
DISPLAY INVISIBLE (-6125 5375);
FORCEPROP 1 LAST HDL_TAP TRUE
J 0
(-5800 5200);
DISPLAY 0.872340 (-5800 5200);
DISPLAY INVISIBLE (-5800 5200);
FORCEPROP 1 LAST PATH I123
J 0
(-6127 5325);
DISPLAY 0.872340 (-6127 5325);
PAINT GREEN (-6127 5325);
DISPLAY INVISIBLE (-6127 5325);
FORCEADD TAP..1
(-6125 5275);
FORCEPROP 3 LASTPIN (-6175 5275) SIG_NAME M_F_CPU1_SA_DQ<26>
J 0
(-6165 5285);
DISPLAY 0.659574 (-6165 5285);
PAINT MONO (-6165 5285);
DISPLAY INVISIBLE (-6165 5285);
FORCEPROP 1 LASTPIN (-6175 5275) BN 26
J 0
(-6187 5283);
DISPLAY 0.489362 (-6187 5283);
PAINT GREEN (-6187 5283);
FORCEPROP 2 LAST CDS_LIB mstr_standard
J 0
(-6125 5275);
DISPLAY 0.723404 (-6125 5275);
PAINT MONO (-6125 5275);
DISPLAY INVISIBLE (-6125 5275);
FORCEPROP 1 LAST BODY_TYPE PLUMBING
J 0
(-6125 5325);
DISPLAY 0.872340 (-6125 5325);
PAINT GREEN (-6125 5325);
DISPLAY INVISIBLE (-6125 5325);
FORCEPROP 1 LAST HDL_TAP TRUE
J 0
(-5800 5150);
DISPLAY 0.872340 (-5800 5150);
DISPLAY INVISIBLE (-5800 5150);
FORCEPROP 1 LAST PATH I124
J 0
(-6127 5275);
DISPLAY 0.872340 (-6127 5275);
PAINT GREEN (-6127 5275);
DISPLAY INVISIBLE (-6127 5275);
FORCEADD TAP..1
(-6125 5525);
FORCEPROP 3 LASTPIN (-6175 5525) SIG_NAME M_F_CPU1_SA_DQ<31>
J 0
(-6165 5535);
DISPLAY 0.659574 (-6165 5535);
PAINT MONO (-6165 5535);
DISPLAY INVISIBLE (-6165 5535);
FORCEPROP 1 LASTPIN (-6175 5525) BN 31
J 0
(-6187 5533);
DISPLAY 0.489362 (-6187 5533);
PAINT GREEN (-6187 5533);
FORCEPROP 2 LAST CDS_LIB mstr_standard
J 0
(-6125 5525);
DISPLAY 0.723404 (-6125 5525);
PAINT MONO (-6125 5525);
DISPLAY INVISIBLE (-6125 5525);
FORCEPROP 1 LAST BODY_TYPE PLUMBING
J 0
(-6125 5575);
DISPLAY 0.872340 (-6125 5575);
PAINT GREEN (-6125 5575);
DISPLAY INVISIBLE (-6125 5575);
FORCEPROP 1 LAST HDL_TAP TRUE
J 0
(-5800 5400);
DISPLAY 0.872340 (-5800 5400);
DISPLAY INVISIBLE (-5800 5400);
FORCEPROP 1 LAST PATH I125
J 0
(-6127 5525);
DISPLAY 0.872340 (-6127 5525);
PAINT GREEN (-6127 5525);
DISPLAY INVISIBLE (-6127 5525);
FORCEADD OFFPAGE..3
(-5375 5575);
FORCEPROP 2 LAST $XR0 42 
J 0
(-5161 5575);
DISPLAY 0.638298 (-5161 5575);
PAINT MONO (-5161 5575);
FORCEPROP 2 LAST CDS_LIB mstr_standard
J 0
(-5375 5575);
DISPLAY 0.723404 (-5375 5575);
PAINT MONO (-5375 5575);
DISPLAY INVISIBLE (-5375 5575);
FORCEPROP 1 LAST OFFPAGE TRUE
J 0
(-5050 5450);
DISPLAY 0.872340 (-5050 5450);
PAINT GREEN (-5050 5450);
DISPLAY INVISIBLE (-5050 5450);
FORCEPROP 1 LAST COMMENT_BODY TRUE
J 0
(-5425 5475);
DISPLAY 0.872340 (-5425 5475);
PAINT GREEN (-5425 5475);
DISPLAY INVISIBLE (-5425 5475);
FORCEPROP 2 LAST PATH I126
J 0
(-5150 5625);
DISPLAY 1.021277 (-5150 5625);
DISPLAY INVISIBLE (-5150 5625);
FORCEADD OFFPAGE..5
(-7325 1450);
FORCEPROP 2 LAST $XR0 103 
J 0
(-7580 1450);
DISPLAY 0.638298 (-7580 1450);
PAINT MONO (-7580 1450);
FORCEPROP 2 LAST BOM_COST MEM
J 0
(-7400 1525);
DISPLAY 0.808511 (-7400 1525);
DISPLAY INVISIBLE (-7400 1525);
FORCEPROP 2 LAST CDS_LIB mstr_standard
J 0
(-7325 1450);
DISPLAY 0.808511 (-7325 1450);
DISPLAY INVISIBLE (-7325 1450);
FORCEPROP 1 LAST OFFPAGE TRUE
J 0
(-7000 1325);
DISPLAY 0.872340 (-7000 1325);
PAINT GREEN (-7000 1325);
DISPLAY INVISIBLE (-7000 1325);
FORCEPROP 1 LAST COMMENT_BODY TRUE
J 0
(-7225 1375);
DISPLAY 0.872340 (-7225 1375);
PAINT GREEN (-7225 1375);
DISPLAY INVISIBLE (-7225 1375);
FORCEPROP 2 LAST PATH I127
J 0
(-7575 1500);
DISPLAY 1.021277 (-7575 1500);
DISPLAY INVISIBLE (-7575 1500);
FORCEADD GND..1
(-6550 1050);
FORCEPROP 3 LASTPIN (-6550 1100) SIG_NAME GND\g
J 0
(-6540 1110);
DISPLAY 0.659574 (-6540 1110);
PAINT MONO (-6540 1110);
DISPLAY INVISIBLE (-6540 1110);
FORCEPROP 1 LAST SIZE 1B
J 0
(-6475 1000);
DISPLAY 0.851064 (-6475 1000);
PAINT GREEN (-6475 1000);
DISPLAY INVISIBLE (-6475 1000);
FORCEPROP 2 LAST CDS_LIB mstr_symbols
J 0
(-6550 1050);
DISPLAY 0.808511 (-6550 1050);
DISPLAY INVISIBLE (-6550 1050);
FORCEPROP 2 LAST BOM_COST MEM
J 0
(-6650 1125);
DISPLAY 0.808511 (-6650 1125);
DISPLAY INVISIBLE (-6650 1125);
FORCEPROP 1 LAST VOLTAGE 0.0
J 0
(-6595 1007);
DISPLAY 0.723404 (-6595 1007);
PAINT SKYBLUE (-6595 1007);
DISPLAY INVISIBLE (-6595 1007);
FORCEPROP 1 LAST BODY_TYPE PLUMBING
J 0
(-6595 1007);
DISPLAY 0.340426 (-6595 1007);
PAINT GREEN (-6595 1007);
DISPLAY INVISIBLE (-6595 1007);
FORCEPROP 1 LAST HDL_POWER GND
J 0
(-6550 1200);
DISPLAY 0.851064 (-6550 1200);
PAINT GREEN (-6550 1200);
DISPLAY INVISIBLE (-6550 1200);
FORCEPROP 1 LAST PATH I128
J 0
(-6475 1050);
DISPLAY 0.872340 (-6475 1050);
PAINT AQUA (-6475 1050);
DISPLAY INVISIBLE (-6475 1050);
FORCEADD Q_RES..2
(-6550 1275);
FORCEPROP 1 LAST LOCATION R773
J 0
(-6505 1400);
DISPLAY 0.489362 (-6505 1400);
PAINT SKYBLUE (-6505 1400);
FORCEPROP 0 LAST $SEC 1
J 0
(-6500 1450);
DISPLAY 0.680851 (-6500 1450);
PAINT MONO (-6500 1450);
DISPLAY INVISIBLE (-6500 1450);
FORCEPROP 0 LAST CDS_SEC 1
J 0
(-6500 1450);
DISPLAY 1.021277 (-6500 1450);
DISPLAY INVISIBLE (-6500 1450);
FORCEPROP 1 LASTPIN (-6550 1375) $PN 1
J 0
(-6545 1337);
DISPLAY 0.489362 (-6545 1337);
PAINT MONO (-6545 1337);
FORCEPROP 1 LASTPIN (-6550 1175) $PN 2
J 0
(-6545 1185);
DISPLAY 0.489362 (-6545 1185);
PAINT MONO (-6545 1185);
FORCEPROP 1 LAST WATTAGE 1/16W
J 0
(-6510 1250);
DISPLAY 0.489362 (-6510 1250);
PAINT SKYBLUE (-6510 1250);
FORCEPROP 1 LAST MATERIAL CHIP
J 0
(-6510 1200);
DISPLAY 0.489362 (-6510 1200);
PAINT SKYBLUE (-6510 1200);
FORCEPROP 1 LAST TOLERANCE 1%
J 0
(-6505 1300);
DISPLAY 0.489362 (-6505 1300);
PAINT SKYBLUE (-6505 1300);
FORCEPROP 1 LAST VALUE 84.5K
J 0
(-6505 1350);
DISPLAY 0.489362 (-6505 1350);
PAINT SKYBLUE (-6505 1350);
FORCEPROP 1 LAST PACK_TYPE 0402LF
J 0
(-6510 1100);
DISPLAY 0.489362 (-6510 1100);
PAINT SKYBLUE (-6510 1100);
FORCEPROP 2 LAST CDS_LIB pure_quanta
J 0
(-6550 1275);
DISPLAY INVISIBLE (-6550 1275);
FORCEPROP 1 LAST PATH I129
J 0
(-6500 1450);
DISPLAY 0.978723 (-6500 1450);
PAINT WHITE (-6500 1450);
DISPLAY INVISIBLE (-6500 1450);
FORCEPROP 1 LAST PART_NUMBER CS38452FB05
J 0
(-6510 1150);
DISPLAY 0.489362 (-6510 1150);
PAINT SKYBLUE (-6510 1150);
DISPLAY INVISIBLE (-6510 1150);
FORCEADD OFFPAGE..1
(-8425 4375);
FORCEPROP 2 LAST $XR0 42 
J 0
(-8646 4375);
DISPLAY 0.638298 (-8646 4375);
PAINT MONO (-8646 4375);
FORCEPROP 2 LAST CDS_LIB mstr_standard
J 0
(-8425 4375);
DISPLAY 0.808511 (-8425 4375);
DISPLAY INVISIBLE (-8425 4375);
FORCEPROP 1 LAST OFFPAGE TRUE
J 0
(-8100 4250);
DISPLAY 0.872340 (-8100 4250);
PAINT GREEN (-8100 4250);
DISPLAY INVISIBLE (-8100 4250);
FORCEPROP 1 LAST COMMENT_BODY TRUE
J 0
(-8300 4275);
DISPLAY 0.872340 (-8300 4275);
PAINT GREEN (-8300 4275);
DISPLAY INVISIBLE (-8300 4275);
FORCEPROP 2 LAST PATH I13
J 0
(-8675 4425);
DISPLAY 1.021277 (-8675 4425);
DISPLAY INVISIBLE (-8675 4425);
FORCEADD OFFPAGE..1
(-8425 4275);
FORCEPROP 2 LAST $XR0 42 
J 0
(-8646 4275);
DISPLAY 0.638298 (-8646 4275);
PAINT MONO (-8646 4275);
FORCEPROP 2 LAST CDS_LIB mstr_standard
J 0
(-8425 4275);
DISPLAY 0.723404 (-8425 4275);
PAINT MONO (-8425 4275);
DISPLAY INVISIBLE (-8425 4275);
FORCEPROP 1 LAST OFFPAGE TRUE
J 0
(-8100 4150);
DISPLAY 0.872340 (-8100 4150);
PAINT GREEN (-8100 4150);
DISPLAY INVISIBLE (-8100 4150);
FORCEPROP 1 LAST COMMENT_BODY TRUE
J 0
(-8300 4175);
DISPLAY 0.872340 (-8300 4175);
PAINT GREEN (-8300 4175);
DISPLAY INVISIBLE (-8300 4175);
FORCEPROP 2 LAST PATH I14
J 0
(-8675 4325);
DISPLAY 1.021277 (-8675 4325);
DISPLAY INVISIBLE (-8675 4325);
FORCEADD GND..1
(-2200 2000);
FORCEPROP 3 LASTPIN (-2200 2050) SIG_NAME GND\g
J 0
(-2190 2060);
DISPLAY 0.659574 (-2190 2060);
PAINT MONO (-2190 2060);
DISPLAY INVISIBLE (-2190 2060);
FORCEPROP 1 LAST SIZE 1B
J 0
(-2125 1950);
DISPLAY 0.851064 (-2125 1950);
PAINT GREEN (-2125 1950);
DISPLAY INVISIBLE (-2125 1950);
FORCEPROP 2 LAST CDS_LIB mstr_symbols
J 0
(-2200 2000);
DISPLAY 0.723404 (-2200 2000);
DISPLAY INVISIBLE (-2200 2000);
FORCEPROP 1 LAST VOLTAGE 0.0
J 0
(-2245 1957);
DISPLAY 0.723404 (-2245 1957);
PAINT SKYBLUE (-2245 1957);
DISPLAY INVISIBLE (-2245 1957);
FORCEPROP 1 LAST BODY_TYPE PLUMBING
J 0
(-2245 1957);
DISPLAY 0.340426 (-2245 1957);
PAINT GREEN (-2245 1957);
DISPLAY INVISIBLE (-2245 1957);
FORCEPROP 1 LAST HDL_POWER GND
J 0
(-2200 2150);
DISPLAY 0.851064 (-2200 2150);
PAINT GREEN (-2200 2150);
DISPLAY INVISIBLE (-2200 2150);
FORCEPROP 1 LAST PATH I140
J 0
(-2125 2000);
DISPLAY 0.872340 (-2125 2000);
PAINT AQUA (-2125 2000);
DISPLAY INVISIBLE (-2125 2000);
FORCEADD GND..1
(-400 1775);
FORCEPROP 3 LASTPIN (-400 1825) SIG_NAME GND\g
J 0
(-390 1835);
DISPLAY 0.659574 (-390 1835);
PAINT MONO (-390 1835);
DISPLAY INVISIBLE (-390 1835);
FORCEPROP 2 LAST CDS_LIB mstr_symbols
J 0
(-400 1775);
DISPLAY 0.723404 (-400 1775);
DISPLAY INVISIBLE (-400 1775);
FORCEPROP 1 LAST SIZE 1B
J 0
(-325 1725);
DISPLAY 0.851064 (-325 1725);
PAINT GREEN (-325 1725);
DISPLAY INVISIBLE (-325 1725);
FORCEPROP 1 LAST VOLTAGE 0.0
J 0
(-445 1732);
DISPLAY 0.723404 (-445 1732);
PAINT SKYBLUE (-445 1732);
DISPLAY INVISIBLE (-445 1732);
FORCEPROP 1 LAST BODY_TYPE PLUMBING
J 0
(-445 1732);
DISPLAY 0.340426 (-445 1732);
PAINT GREEN (-445 1732);
DISPLAY INVISIBLE (-445 1732);
FORCEPROP 1 LAST HDL_POWER GND
J 0
(-400 1925);
DISPLAY 0.851064 (-400 1925);
PAINT GREEN (-400 1925);
DISPLAY INVISIBLE (-400 1925);
FORCEPROP 1 LAST PATH I141
J 0
(-325 1775);
DISPLAY 0.872340 (-325 1775);
PAINT AQUA (-325 1775);
DISPLAY INVISIBLE (-325 1775);
FORCEADD SCONN288_DDR506112002KQ..3
(-1300 3775);
FORCEPROP 1 LAST LOCATION J33
J 0
(-1750 5750);
DISPLAY 0.468085 (-1750 5750);
PAINT SKYBLUE (-1750 5750);
FORCEPROP 0 LAST $SEC 3
J 0
(-1750 5900);
DISPLAY 0.680851 (-1750 5900);
PAINT MONO (-1750 5900);
DISPLAY INVISIBLE (-1750 5900);
FORCEPROP 2 LAST CDS_SEC 3
J 0
(-1750 5900);
DISPLAY 1.021277 (-1750 5900);
DISPLAY INVISIBLE (-1750 5900);
FORCEPROP 0 LASTPIN (-700 2175) $PN G1
J 0
(-690 2185);
DISPLAY 0.680851 (-690 2185);
PAINT MONO (-690 2185);
FORCEPROP 0 LASTPIN (-700 2125) $PN G2
J 0
(-690 2135);
DISPLAY 0.680851 (-690 2135);
PAINT MONO (-690 2135);
FORCEPROP 0 LASTPIN (-700 2075) $PN G3
J 0
(-690 2085);
DISPLAY 0.680851 (-690 2085);
PAINT MONO (-690 2085);
FORCEPROP 0 LASTPIN (-1900 5325) $PN 1
J 2
(-1910 5335);
DISPLAY 0.680851 (-1910 5335);
PAINT MONO (-1910 5335);
FORCEPROP 0 LASTPIN (-1900 5375) $PN 145
J 2
(-1910 5385);
DISPLAY 0.680851 (-1910 5385);
PAINT MONO (-1910 5385);
FORCEPROP 0 LASTPIN (-1900 5425) $PN 146
J 2
(-1910 5435);
DISPLAY 0.680851 (-1910 5435);
PAINT MONO (-1910 5435);
FORCEPROP 0 LASTPIN (-700 2275) $PN 6
J 0
(-690 2285);
DISPLAY 0.680851 (-690 2285);
PAINT MONO (-690 2285);
FORCEPROP 0 LASTPIN (-700 2325) $PN 8
J 0
(-690 2335);
DISPLAY 0.680851 (-690 2335);
PAINT MONO (-690 2335);
FORCEPROP 0 LASTPIN (-700 2375) $PN 10
J 0
(-690 2385);
DISPLAY 0.680851 (-690 2385);
PAINT MONO (-690 2385);
FORCEPROP 0 LASTPIN (-700 2425) $PN 13
J 0
(-690 2435);
DISPLAY 0.680851 (-690 2435);
PAINT MONO (-690 2435);
FORCEPROP 0 LASTPIN (-700 2475) $PN 15
J 0
(-690 2485);
DISPLAY 0.680851 (-690 2485);
PAINT MONO (-690 2485);
FORCEPROP 0 LASTPIN (-700 2525) $PN 17
J 0
(-690 2535);
DISPLAY 0.680851 (-690 2535);
PAINT MONO (-690 2535);
FORCEPROP 0 LASTPIN (-700 2575) $PN 19
J 0
(-690 2585);
DISPLAY 0.680851 (-690 2585);
PAINT MONO (-690 2585);
FORCEPROP 0 LASTPIN (-700 2625) $PN 21
J 0
(-690 2635);
DISPLAY 0.680851 (-690 2635);
PAINT MONO (-690 2635);
FORCEPROP 0 LASTPIN (-700 2675) $PN 24
J 0
(-690 2685);
DISPLAY 0.680851 (-690 2685);
PAINT MONO (-690 2685);
FORCEPROP 0 LASTPIN (-700 2725) $PN 26
J 0
(-690 2735);
DISPLAY 0.680851 (-690 2735);
PAINT MONO (-690 2735);
FORCEPROP 0 LASTPIN (-700 2775) $PN 28
J 0
(-690 2785);
DISPLAY 0.680851 (-690 2785);
PAINT MONO (-690 2785);
FORCEPROP 0 LASTPIN (-700 2825) $PN 30
J 0
(-690 2835);
DISPLAY 0.680851 (-690 2835);
PAINT MONO (-690 2835);
FORCEPROP 0 LASTPIN (-700 2875) $PN 32
J 0
(-690 2885);
DISPLAY 0.680851 (-690 2885);
PAINT MONO (-690 2885);
FORCEPROP 0 LASTPIN (-700 2925) $PN 35
J 0
(-690 2935);
DISPLAY 0.680851 (-690 2935);
PAINT MONO (-690 2935);
FORCEPROP 0 LASTPIN (-700 2975) $PN 37
J 0
(-690 2985);
DISPLAY 0.680851 (-690 2985);
PAINT MONO (-690 2985);
FORCEPROP 0 LASTPIN (-700 3025) $PN 39
J 0
(-690 3035);
DISPLAY 0.680851 (-690 3035);
PAINT MONO (-690 3035);
FORCEPROP 0 LASTPIN (-700 3075) $PN 41
J 0
(-690 3085);
DISPLAY 0.680851 (-690 3085);
PAINT MONO (-690 3085);
FORCEPROP 0 LASTPIN (-700 3125) $PN 43
J 0
(-690 3135);
DISPLAY 0.680851 (-690 3135);
PAINT MONO (-690 3135);
FORCEPROP 0 LASTPIN (-700 3175) $PN 46
J 0
(-690 3185);
DISPLAY 0.680851 (-690 3185);
PAINT MONO (-690 3185);
FORCEPROP 0 LASTPIN (-700 3225) $PN 48
J 0
(-690 3235);
DISPLAY 0.680851 (-690 3235);
PAINT MONO (-690 3235);
FORCEPROP 0 LASTPIN (-700 3275) $PN 50
J 0
(-690 3285);
DISPLAY 0.680851 (-690 3285);
PAINT MONO (-690 3285);
FORCEPROP 0 LASTPIN (-700 3325) $PN 52
J 0
(-690 3335);
DISPLAY 0.680851 (-690 3335);
PAINT MONO (-690 3335);
FORCEPROP 0 LASTPIN (-700 3375) $PN 54
J 0
(-690 3385);
DISPLAY 0.680851 (-690 3385);
PAINT MONO (-690 3385);
FORCEPROP 0 LASTPIN (-700 3425) $PN 57
J 0
(-690 3435);
DISPLAY 0.680851 (-690 3435);
PAINT MONO (-690 3435);
FORCEPROP 0 LASTPIN (-700 3475) $PN 59
J 0
(-690 3485);
DISPLAY 0.680851 (-690 3485);
PAINT MONO (-690 3485);
FORCEPROP 0 LASTPIN (-700 3525) $PN 61
J 0
(-690 3535);
DISPLAY 0.680851 (-690 3535);
PAINT MONO (-690 3535);
FORCEPROP 0 LASTPIN (-700 3575) $PN 63
J 0
(-690 3585);
DISPLAY 0.680851 (-690 3585);
PAINT MONO (-690 3585);
FORCEPROP 0 LASTPIN (-700 3625) $PN 65
J 0
(-690 3635);
DISPLAY 0.680851 (-690 3635);
PAINT MONO (-690 3635);
FORCEPROP 0 LASTPIN (-700 3675) $PN 67
J 0
(-690 3685);
DISPLAY 0.680851 (-690 3685);
PAINT MONO (-690 3685);
FORCEPROP 0 LASTPIN (-700 3725) $PN 69
J 0
(-690 3735);
DISPLAY 0.680851 (-690 3735);
PAINT MONO (-690 3735);
FORCEPROP 0 LASTPIN (-700 3775) $PN 71
J 0
(-690 3785);
DISPLAY 0.680851 (-690 3785);
PAINT MONO (-690 3785);
FORCEPROP 0 LASTPIN (-700 3825) $PN 73
J 0
(-690 3835);
DISPLAY 0.680851 (-690 3835);
PAINT MONO (-690 3835);
FORCEPROP 0 LASTPIN (-700 3875) $PN 75
J 0
(-690 3885);
DISPLAY 0.680851 (-690 3885);
PAINT MONO (-690 3885);
FORCEPROP 0 LASTPIN (-700 3925) $PN 77
J 0
(-690 3935);
DISPLAY 0.680851 (-690 3935);
PAINT MONO (-690 3935);
FORCEPROP 0 LASTPIN (-700 3975) $PN 79
J 0
(-690 3985);
DISPLAY 0.680851 (-690 3985);
PAINT MONO (-690 3985);
FORCEPROP 0 LASTPIN (-700 4025) $PN 81
J 0
(-690 4035);
DISPLAY 0.680851 (-690 4035);
PAINT MONO (-690 4035);
FORCEPROP 0 LASTPIN (-700 4075) $PN 83
J 0
(-690 4085);
DISPLAY 0.680851 (-690 4085);
PAINT MONO (-690 4085);
FORCEPROP 0 LASTPIN (-700 4125) $PN 85
J 0
(-690 4135);
DISPLAY 0.680851 (-690 4135);
PAINT MONO (-690 4135);
FORCEPROP 0 LASTPIN (-700 4175) $PN 88
J 0
(-690 4185);
DISPLAY 0.680851 (-690 4185);
PAINT MONO (-690 4185);
FORCEPROP 0 LASTPIN (-700 4225) $PN 90
J 0
(-690 4235);
DISPLAY 0.680851 (-690 4235);
PAINT MONO (-690 4235);
FORCEPROP 0 LASTPIN (-700 4275) $PN 92
J 0
(-690 4285);
DISPLAY 0.680851 (-690 4285);
PAINT MONO (-690 4285);
FORCEPROP 0 LASTPIN (-700 4325) $PN 95
J 0
(-690 4335);
DISPLAY 0.680851 (-690 4335);
PAINT MONO (-690 4335);
FORCEPROP 0 LASTPIN (-700 4375) $PN 97
J 0
(-690 4385);
DISPLAY 0.680851 (-690 4385);
PAINT MONO (-690 4385);
FORCEPROP 0 LASTPIN (-700 4425) $PN 99
J 0
(-690 4435);
DISPLAY 0.680851 (-690 4435);
PAINT MONO (-690 4435);
FORCEPROP 0 LASTPIN (-700 4475) $PN 101
J 0
(-690 4485);
DISPLAY 0.680851 (-690 4485);
PAINT MONO (-690 4485);
FORCEPROP 0 LASTPIN (-700 4525) $PN 103
J 0
(-690 4535);
DISPLAY 0.680851 (-690 4535);
PAINT MONO (-690 4535);
FORCEPROP 0 LASTPIN (-700 4575) $PN 106
J 0
(-690 4585);
DISPLAY 0.680851 (-690 4585);
PAINT MONO (-690 4585);
FORCEPROP 0 LASTPIN (-700 4625) $PN 108
J 0
(-690 4635);
DISPLAY 0.680851 (-690 4635);
PAINT MONO (-690 4635);
FORCEPROP 0 LASTPIN (-700 4675) $PN 110
J 0
(-690 4685);
DISPLAY 0.680851 (-690 4685);
PAINT MONO (-690 4685);
FORCEPROP 0 LASTPIN (-700 4725) $PN 112
J 0
(-690 4735);
DISPLAY 0.680851 (-690 4735);
PAINT MONO (-690 4735);
FORCEPROP 0 LASTPIN (-700 4775) $PN 114
J 0
(-690 4785);
DISPLAY 0.680851 (-690 4785);
PAINT MONO (-690 4785);
FORCEPROP 0 LASTPIN (-700 4825) $PN 117
J 0
(-690 4835);
DISPLAY 0.680851 (-690 4835);
PAINT MONO (-690 4835);
FORCEPROP 0 LASTPIN (-700 4875) $PN 119
J 0
(-690 4885);
DISPLAY 0.680851 (-690 4885);
PAINT MONO (-690 4885);
FORCEPROP 0 LASTPIN (-700 4925) $PN 121
J 0
(-690 4935);
DISPLAY 0.680851 (-690 4935);
PAINT MONO (-690 4935);
FORCEPROP 0 LASTPIN (-700 4975) $PN 123
J 0
(-690 4985);
DISPLAY 0.680851 (-690 4985);
PAINT MONO (-690 4985);
FORCEPROP 0 LASTPIN (-700 5025) $PN 125
J 0
(-690 5035);
DISPLAY 0.680851 (-690 5035);
PAINT MONO (-690 5035);
FORCEPROP 0 LASTPIN (-700 5075) $PN 128
J 0
(-690 5085);
DISPLAY 0.680851 (-690 5085);
PAINT MONO (-690 5085);
FORCEPROP 0 LASTPIN (-700 5125) $PN 130
J 0
(-690 5135);
DISPLAY 0.680851 (-690 5135);
PAINT MONO (-690 5135);
FORCEPROP 0 LASTPIN (-700 5175) $PN 132
J 0
(-690 5185);
DISPLAY 0.680851 (-690 5185);
PAINT MONO (-690 5185);
FORCEPROP 0 LASTPIN (-700 5225) $PN 134
J 0
(-690 5235);
DISPLAY 0.680851 (-690 5235);
PAINT MONO (-690 5235);
FORCEPROP 0 LASTPIN (-700 5275) $PN 136
J 0
(-690 5285);
DISPLAY 0.680851 (-690 5285);
PAINT MONO (-690 5285);
FORCEPROP 0 LASTPIN (-700 5325) $PN 139
J 0
(-690 5335);
DISPLAY 0.680851 (-690 5335);
PAINT MONO (-690 5335);
FORCEPROP 0 LASTPIN (-700 5375) $PN 141
J 0
(-690 5385);
DISPLAY 0.680851 (-690 5385);
PAINT MONO (-690 5385);
FORCEPROP 0 LASTPIN (-700 5425) $PN 143
J 0
(-690 5435);
DISPLAY 0.680851 (-690 5435);
PAINT MONO (-690 5435);
FORCEPROP 0 LASTPIN (-1900 2175) $PN 151
J 2
(-1910 2185);
DISPLAY 0.680851 (-1910 2185);
PAINT MONO (-1910 2185);
FORCEPROP 0 LASTPIN (-1900 2225) $PN 153
J 2
(-1910 2235);
DISPLAY 0.680851 (-1910 2235);
PAINT MONO (-1910 2235);
FORCEPROP 0 LASTPIN (-1900 2275) $PN 155
J 2
(-1910 2285);
DISPLAY 0.680851 (-1910 2285);
PAINT MONO (-1910 2285);
FORCEPROP 0 LASTPIN (-1900 2325) $PN 158
J 2
(-1910 2335);
DISPLAY 0.680851 (-1910 2335);
PAINT MONO (-1910 2335);
FORCEPROP 0 LASTPIN (-1900 2375) $PN 160
J 2
(-1910 2385);
DISPLAY 0.680851 (-1910 2385);
PAINT MONO (-1910 2385);
FORCEPROP 0 LASTPIN (-1900 2425) $PN 162
J 2
(-1910 2435);
DISPLAY 0.680851 (-1910 2435);
PAINT MONO (-1910 2435);
FORCEPROP 0 LASTPIN (-1900 2475) $PN 164
J 2
(-1910 2485);
DISPLAY 0.680851 (-1910 2485);
PAINT MONO (-1910 2485);
FORCEPROP 0 LASTPIN (-1900 2525) $PN 166
J 2
(-1910 2535);
DISPLAY 0.680851 (-1910 2535);
PAINT MONO (-1910 2535);
FORCEPROP 0 LASTPIN (-1900 2575) $PN 169
J 2
(-1910 2585);
DISPLAY 0.680851 (-1910 2585);
PAINT MONO (-1910 2585);
FORCEPROP 0 LASTPIN (-1900 2625) $PN 171
J 2
(-1910 2635);
DISPLAY 0.680851 (-1910 2635);
PAINT MONO (-1910 2635);
FORCEPROP 0 LASTPIN (-1900 2675) $PN 173
J 2
(-1910 2685);
DISPLAY 0.680851 (-1910 2685);
PAINT MONO (-1910 2685);
FORCEPROP 0 LASTPIN (-1900 2725) $PN 175
J 2
(-1910 2735);
DISPLAY 0.680851 (-1910 2735);
PAINT MONO (-1910 2735);
FORCEPROP 0 LASTPIN (-1900 2775) $PN 177
J 2
(-1910 2785);
DISPLAY 0.680851 (-1910 2785);
PAINT MONO (-1910 2785);
FORCEPROP 0 LASTPIN (-1900 2825) $PN 180
J 2
(-1910 2835);
DISPLAY 0.680851 (-1910 2835);
PAINT MONO (-1910 2835);
FORCEPROP 0 LASTPIN (-1900 2875) $PN 182
J 2
(-1910 2885);
DISPLAY 0.680851 (-1910 2885);
PAINT MONO (-1910 2885);
FORCEPROP 0 LASTPIN (-1900 2925) $PN 184
J 2
(-1910 2935);
DISPLAY 0.680851 (-1910 2935);
PAINT MONO (-1910 2935);
FORCEPROP 0 LASTPIN (-1900 2975) $PN 186
J 2
(-1910 2985);
DISPLAY 0.680851 (-1910 2985);
PAINT MONO (-1910 2985);
FORCEPROP 0 LASTPIN (-1900 3025) $PN 188
J 2
(-1910 3035);
DISPLAY 0.680851 (-1910 3035);
PAINT MONO (-1910 3035);
FORCEPROP 0 LASTPIN (-1900 3075) $PN 191
J 2
(-1910 3085);
DISPLAY 0.680851 (-1910 3085);
PAINT MONO (-1910 3085);
FORCEPROP 0 LASTPIN (-1900 3125) $PN 193
J 2
(-1910 3135);
DISPLAY 0.680851 (-1910 3135);
PAINT MONO (-1910 3135);
FORCEPROP 0 LASTPIN (-1900 3175) $PN 195
J 2
(-1910 3185);
DISPLAY 0.680851 (-1910 3185);
PAINT MONO (-1910 3185);
FORCEPROP 0 LASTPIN (-1900 3225) $PN 197
J 2
(-1910 3235);
DISPLAY 0.680851 (-1910 3235);
PAINT MONO (-1910 3235);
FORCEPROP 0 LASTPIN (-1900 3275) $PN 199
J 2
(-1910 3285);
DISPLAY 0.680851 (-1910 3285);
PAINT MONO (-1910 3285);
FORCEPROP 0 LASTPIN (-1900 3325) $PN 202
J 2
(-1910 3335);
DISPLAY 0.680851 (-1910 3335);
PAINT MONO (-1910 3335);
FORCEPROP 0 LASTPIN (-1900 3375) $PN 204
J 2
(-1910 3385);
DISPLAY 0.680851 (-1910 3385);
PAINT MONO (-1910 3385);
FORCEPROP 0 LASTPIN (-1900 3425) $PN 206
J 2
(-1910 3435);
DISPLAY 0.680851 (-1910 3435);
PAINT MONO (-1910 3435);
FORCEPROP 0 LASTPIN (-1900 3475) $PN 208
J 2
(-1910 3485);
DISPLAY 0.680851 (-1910 3485);
PAINT MONO (-1910 3485);
FORCEPROP 0 LASTPIN (-1900 3525) $PN 210
J 2
(-1910 3535);
DISPLAY 0.680851 (-1910 3535);
PAINT MONO (-1910 3535);
FORCEPROP 0 LASTPIN (-1900 3575) $PN 212
J 2
(-1910 3585);
DISPLAY 0.680851 (-1910 3585);
PAINT MONO (-1910 3585);
FORCEPROP 0 LASTPIN (-1900 3625) $PN 214
J 2
(-1910 3635);
DISPLAY 0.680851 (-1910 3635);
PAINT MONO (-1910 3635);
FORCEPROP 0 LASTPIN (-1900 3675) $PN 216
J 2
(-1910 3685);
DISPLAY 0.680851 (-1910 3685);
PAINT MONO (-1910 3685);
FORCEPROP 0 LASTPIN (-1900 3725) $PN 219
J 2
(-1910 3735);
DISPLAY 0.680851 (-1910 3735);
PAINT MONO (-1910 3735);
FORCEPROP 0 LASTPIN (-1900 3775) $PN 222
J 2
(-1910 3785);
DISPLAY 0.680851 (-1910 3785);
PAINT MONO (-1910 3785);
FORCEPROP 0 LASTPIN (-1900 3825) $PN 224
J 2
(-1910 3835);
DISPLAY 0.680851 (-1910 3835);
PAINT MONO (-1910 3835);
FORCEPROP 0 LASTPIN (-1900 3875) $PN 226
J 2
(-1910 3885);
DISPLAY 0.680851 (-1910 3885);
PAINT MONO (-1910 3885);
FORCEPROP 0 LASTPIN (-1900 3925) $PN 228
J 2
(-1910 3935);
DISPLAY 0.680851 (-1910 3935);
PAINT MONO (-1910 3935);
FORCEPROP 0 LASTPIN (-1900 3975) $PN 230
J 2
(-1910 3985);
DISPLAY 0.680851 (-1910 3985);
PAINT MONO (-1910 3985);
FORCEPROP 0 LASTPIN (-1900 4025) $PN 233
J 2
(-1910 4035);
DISPLAY 0.680851 (-1910 4035);
PAINT MONO (-1910 4035);
FORCEPROP 0 LASTPIN (-1900 4075) $PN 235
J 2
(-1910 4085);
DISPLAY 0.680851 (-1910 4085);
PAINT MONO (-1910 4085);
FORCEPROP 0 LASTPIN (-1900 4125) $PN 237
J 2
(-1910 4135);
DISPLAY 0.680851 (-1910 4135);
PAINT MONO (-1910 4135);
FORCEPROP 0 LASTPIN (-1900 4175) $PN 240
J 2
(-1910 4185);
DISPLAY 0.680851 (-1910 4185);
PAINT MONO (-1910 4185);
FORCEPROP 0 LASTPIN (-1900 4225) $PN 242
J 2
(-1910 4235);
DISPLAY 0.680851 (-1910 4235);
PAINT MONO (-1910 4235);
FORCEPROP 0 LASTPIN (-1900 4275) $PN 244
J 2
(-1910 4285);
DISPLAY 0.680851 (-1910 4285);
PAINT MONO (-1910 4285);
FORCEPROP 0 LASTPIN (-1900 4325) $PN 246
J 2
(-1910 4335);
DISPLAY 0.680851 (-1910 4335);
PAINT MONO (-1910 4335);
FORCEPROP 0 LASTPIN (-1900 4375) $PN 248
J 2
(-1910 4385);
DISPLAY 0.680851 (-1910 4385);
PAINT MONO (-1910 4385);
FORCEPROP 0 LASTPIN (-1900 4425) $PN 251
J 2
(-1910 4435);
DISPLAY 0.680851 (-1910 4435);
PAINT MONO (-1910 4435);
FORCEPROP 0 LASTPIN (-1900 4475) $PN 253
J 2
(-1910 4485);
DISPLAY 0.680851 (-1910 4485);
PAINT MONO (-1910 4485);
FORCEPROP 0 LASTPIN (-1900 4525) $PN 255
J 2
(-1910 4535);
DISPLAY 0.680851 (-1910 4535);
PAINT MONO (-1910 4535);
FORCEPROP 0 LASTPIN (-1900 4575) $PN 257
J 2
(-1910 4585);
DISPLAY 0.680851 (-1910 4585);
PAINT MONO (-1910 4585);
FORCEPROP 0 LASTPIN (-1900 4625) $PN 259
J 2
(-1910 4635);
DISPLAY 0.680851 (-1910 4635);
PAINT MONO (-1910 4635);
FORCEPROP 0 LASTPIN (-1900 4675) $PN 262
J 2
(-1910 4685);
DISPLAY 0.680851 (-1910 4685);
PAINT MONO (-1910 4685);
FORCEPROP 0 LASTPIN (-1900 4725) $PN 264
J 2
(-1910 4735);
DISPLAY 0.680851 (-1910 4735);
PAINT MONO (-1910 4735);
FORCEPROP 0 LASTPIN (-1900 4775) $PN 266
J 2
(-1910 4785);
DISPLAY 0.680851 (-1910 4785);
PAINT MONO (-1910 4785);
FORCEPROP 0 LASTPIN (-1900 4825) $PN 268
J 2
(-1910 4835);
DISPLAY 0.680851 (-1910 4835);
PAINT MONO (-1910 4835);
FORCEPROP 0 LASTPIN (-1900 4875) $PN 270
J 2
(-1910 4885);
DISPLAY 0.680851 (-1910 4885);
PAINT MONO (-1910 4885);
FORCEPROP 0 LASTPIN (-1900 4925) $PN 273
J 2
(-1910 4935);
DISPLAY 0.680851 (-1910 4935);
PAINT MONO (-1910 4935);
FORCEPROP 0 LASTPIN (-1900 4975) $PN 275
J 2
(-1910 4985);
DISPLAY 0.680851 (-1910 4985);
PAINT MONO (-1910 4985);
FORCEPROP 0 LASTPIN (-1900 5025) $PN 277
J 2
(-1910 5035);
DISPLAY 0.680851 (-1910 5035);
PAINT MONO (-1910 5035);
FORCEPROP 0 LASTPIN (-1900 5075) $PN 279
J 2
(-1910 5085);
DISPLAY 0.680851 (-1910 5085);
PAINT MONO (-1910 5085);
FORCEPROP 0 LASTPIN (-1900 5125) $PN 281
J 2
(-1910 5135);
DISPLAY 0.680851 (-1910 5135);
PAINT MONO (-1910 5135);
FORCEPROP 0 LASTPIN (-1900 5175) $PN 284
J 2
(-1910 5185);
DISPLAY 0.680851 (-1910 5185);
PAINT MONO (-1910 5185);
FORCEPROP 0 LASTPIN (-1900 5225) $PN 286
J 2
(-1910 5235);
DISPLAY 0.680851 (-1910 5235);
PAINT MONO (-1910 5235);
FORCEPROP 0 LASTPIN (-1900 5275) $PN 288
J 2
(-1910 5285);
DISPLAY 0.680851 (-1910 5285);
PAINT MONO (-1910 5285);
FORCEPROP 2 LAST PART_TYPE SMLF
J 0
(-1750 5850);
DISPLAY 1.021277 (-1750 5850);
FORCEPROP 2 LAST VALUE SCONN288_DDR506112002KQ
J 0
(-1750 5800);
DISPLAY 0.489362 (-1750 5800);
PAINT SKYBLUE (-1750 5800);
FORCEPROP 1 LAST MATERIAL IO
J 0
(-1750 5600);
DISPLAY 0.468085 (-1750 5600);
PAINT SKYBLUE (-1750 5600);
FORCEPROP 1 LAST CDS_LMAN_SYM_OUTLINE -450,1800,450,-1750
J 0
(-1300 3775);
DISPLAY 0.468085 (-1300 3775);
PAINT GREEN (-1300 3775);
DISPLAY INVISIBLE (-1300 3775);
FORCEPROP 1 LAST NEEDS_NO_SIZE TRUE
J 0
(-1300 3775);
DISPLAY 0.723404 (-1300 3775);
PAINT GREEN (-1300 3775);
DISPLAY INVISIBLE (-1300 3775);
FORCEPROP 2 LAST CDS_LIB pure_quanta
J 0
(-1300 3775);
DISPLAY INVISIBLE (-1300 3775);
FORCEPROP 1 LAST PATH I142
J 0
(-1300 3775);
DISPLAY 0.723404 (-1300 3775);
PAINT GREEN (-1300 3775);
DISPLAY INVISIBLE (-1300 3775);
FORCEPROP 1 LAST PART_NUMBER DFHST8FS479
J 0
(-1750 5675);
DISPLAY 0.468085 (-1750 5675);
PAINT SKYBLUE (-1750 5675);
DISPLAY INVISIBLE (-1750 5675);
FORCEADD OFFPAGE..1
(-8425 4425);
FORCEPROP 2 LAST $XR0 42 
J 0
(-8646 4425);
DISPLAY 0.638298 (-8646 4425);
PAINT MONO (-8646 4425);
FORCEPROP 2 LAST CDS_LIB mstr_standard
J 0
(-8425 4425);
DISPLAY 0.723404 (-8425 4425);
PAINT MONO (-8425 4425);
DISPLAY INVISIBLE (-8425 4425);
FORCEPROP 1 LAST OFFPAGE TRUE
J 0
(-8100 4300);
DISPLAY 0.872340 (-8100 4300);
PAINT GREEN (-8100 4300);
DISPLAY INVISIBLE (-8100 4300);
FORCEPROP 1 LAST COMMENT_BODY TRUE
J 0
(-8300 4325);
DISPLAY 0.872340 (-8300 4325);
PAINT GREEN (-8300 4325);
DISPLAY INVISIBLE (-8300 4325);
FORCEPROP 2 LAST PATH I15
J 0
(-8675 4475);
DISPLAY 1.021277 (-8675 4475);
DISPLAY INVISIBLE (-8675 4475);
FORCEADD OFFPAGE..1
(-8425 4675);
FORCEPROP 2 LAST $XR0 42 
J 0
(-8646 4675);
DISPLAY 0.638298 (-8646 4675);
PAINT MONO (-8646 4675);
FORCEPROP 2 LAST CDS_LIB mstr_standard
J 0
(-8425 4675);
DISPLAY 0.808511 (-8425 4675);
DISPLAY INVISIBLE (-8425 4675);
FORCEPROP 1 LAST OFFPAGE TRUE
J 0
(-8100 4550);
DISPLAY 0.872340 (-8100 4550);
PAINT GREEN (-8100 4550);
DISPLAY INVISIBLE (-8100 4550);
FORCEPROP 1 LAST COMMENT_BODY TRUE
J 0
(-8300 4575);
DISPLAY 0.872340 (-8300 4575);
PAINT GREEN (-8300 4575);
DISPLAY INVISIBLE (-8300 4575);
FORCEPROP 2 LAST PATH I16
J 0
(-8675 4725);
DISPLAY 1.021277 (-8675 4725);
DISPLAY INVISIBLE (-8675 4725);
FORCEADD OFFPAGE..1
(-8425 4525);
FORCEPROP 2 LAST $XR0 42 
J 0
(-8646 4525);
DISPLAY 0.638298 (-8646 4525);
PAINT MONO (-8646 4525);
FORCEPROP 2 LAST CDS_LIB mstr_standard
J 0
(-8425 4525);
DISPLAY 0.808511 (-8425 4525);
DISPLAY INVISIBLE (-8425 4525);
FORCEPROP 1 LAST OFFPAGE TRUE
J 0
(-8100 4400);
DISPLAY 0.872340 (-8100 4400);
PAINT GREEN (-8100 4400);
DISPLAY INVISIBLE (-8100 4400);
FORCEPROP 1 LAST COMMENT_BODY TRUE
J 0
(-8300 4425);
DISPLAY 0.872340 (-8300 4425);
PAINT GREEN (-8300 4425);
DISPLAY INVISIBLE (-8300 4425);
FORCEPROP 2 LAST PATH I17
J 0
(-8675 4575);
DISPLAY 1.021277 (-8675 4575);
DISPLAY INVISIBLE (-8675 4575);
FORCEADD OFFPAGE..1
(-8425 4575);
FORCEPROP 2 LAST $XR0 42 
J 0
(-8646 4575);
DISPLAY 0.638298 (-8646 4575);
PAINT MONO (-8646 4575);
FORCEPROP 2 LAST CDS_LIB mstr_standard
J 0
(-8425 4575);
DISPLAY 0.723404 (-8425 4575);
PAINT MONO (-8425 4575);
DISPLAY INVISIBLE (-8425 4575);
FORCEPROP 1 LAST OFFPAGE TRUE
J 0
(-8100 4450);
DISPLAY 0.872340 (-8100 4450);
PAINT GREEN (-8100 4450);
DISPLAY INVISIBLE (-8100 4450);
FORCEPROP 1 LAST COMMENT_BODY TRUE
J 0
(-8300 4475);
DISPLAY 0.872340 (-8300 4475);
PAINT GREEN (-8300 4475);
DISPLAY INVISIBLE (-8300 4475);
FORCEPROP 2 LAST PATH I18
J 0
(-8675 4625);
DISPLAY 1.021277 (-8675 4625);
DISPLAY INVISIBLE (-8675 4625);
FORCEADD Q_CAP..1
R 2
(-8675 3350);
FORCEPROP 1 LAST LOCATION C156
J 2
(-8725 3450);
DISPLAY 0.489362 (-8725 3450);
PAINT SKYBLUE (-8725 3450);
FORCEPROP 0 LAST $SEC 1
J 0
(-8725 3500);
DISPLAY 0.680851 (-8725 3500);
PAINT MONO (-8725 3500);
DISPLAY INVISIBLE (-8725 3500);
FORCEPROP 0 LAST CDS_SEC 1
J 0
(-8725 3500);
DISPLAY 1.021277 (-8725 3500);
DISPLAY INVISIBLE (-8725 3500);
FORCEPROP 1 LASTPIN (-8675 3450) $PN 1
J 2
(-8685 3430);
DISPLAY 0.489362 (-8685 3430);
PAINT MONO (-8685 3430);
FORCEPROP 1 LASTPIN (-8675 3250) $PN 2
J 2
(-8685 3230);
DISPLAY 0.489362 (-8685 3230);
PAINT MONO (-8685 3230);
FORCEPROP 1 LAST PACK_TYPE 0402
J 2
(-8725 3150);
DISPLAY 0.489362 (-8725 3150);
PAINT SKYBLUE (-8725 3150);
FORCEPROP 1 LAST VALUE 0.1UF
J 2
(-8725 3400);
DISPLAY 0.489362 (-8725 3400);
PAINT SKYBLUE (-8725 3400);
FORCEPROP 1 LAST MATERIAL X7R
J 2
(-8725 3250);
DISPLAY 0.489362 (-8725 3250);
PAINT SKYBLUE (-8725 3250);
FORCEPROP 1 LAST VOLTAGE 25V
J 2
(-8725 3350);
DISPLAY 0.489362 (-8725 3350);
PAINT SKYBLUE (-8725 3350);
FORCEPROP 1 LAST TOLERANCE 10%
J 2
(-8725 3300);
DISPLAY 0.489362 (-8725 3300);
PAINT SKYBLUE (-8725 3300);
FORCEPROP 2 LAST CDS_LIB pure_quanta
J 0
(-8675 3350);
DISPLAY INVISIBLE (-8675 3350);
FORCEPROP 0 LAST BOM_COST MEM
J 2
(-8730 3495);
DISPLAY 0.595745 (-8730 3495);
PAINT MONO (-8730 3495);
DISPLAY INVISIBLE (-8730 3495);
FORCEPROP 2 LAST ROOM 
J 2
(-8730 3495);
DISPLAY 0.595745 (-8730 3495);
PAINT RED (-8730 3495);
DISPLAY INVISIBLE (-8730 3495);
FORCEPROP 1 LAST PATH I185
J 2
(-8725 3500);
DISPLAY 0.978723 (-8725 3500);
PAINT WHITE (-8725 3500);
DISPLAY INVISIBLE (-8725 3500);
FORCEPROP 1 LAST PART_NUMBER CH4104K1B00
J 2
(-8725 3200);
DISPLAY 0.489362 (-8725 3200);
PAINT SKYBLUE (-8725 3200);
DISPLAY INVISIBLE (-8725 3200);
FORCEADD GND..1
(-8675 3125);
FORCEPROP 3 LASTPIN (-8675 3175) SIG_NAME GND\g
J 0
(-8665 3185);
DISPLAY 0.659574 (-8665 3185);
PAINT MONO (-8665 3185);
DISPLAY INVISIBLE (-8665 3185);
FORCEPROP 2 LAST BOM_COST MEM
J 0
(-8650 3250);
DISPLAY 0.659574 (-8650 3250);
DISPLAY INVISIBLE (-8650 3250);
FORCEPROP 1 LAST SIZE 1B
J 0
(-8600 3075);
DISPLAY 0.723404 (-8600 3075);
PAINT GREEN (-8600 3075);
DISPLAY INVISIBLE (-8600 3075);
FORCEPROP 2 LAST CDS_LIB mstr_symbols
J 0
(-8675 3125);
DISPLAY 0.808511 (-8675 3125);
DISPLAY INVISIBLE (-8675 3125);
FORCEPROP 1 LAST VOLTAGE 0
J 0
(-8695 3220);
DISPLAY 0.829787 (-8695 3220);
PAINT SKYBLUE (-8695 3220);
DISPLAY INVISIBLE (-8695 3220);
FORCEPROP 2 LAST ROOM MEM_EFGH_DECOUPLING_CAPS
J 0
(-8650 3200);
DISPLAY 0.659574 (-8650 3200);
PAINT RED (-8650 3200);
DISPLAY INVISIBLE (-8650 3200);
FORCEPROP 1 LAST BODY_TYPE PLUMBING
J 0
(-8720 3082);
DISPLAY 0.276596 (-8720 3082);
PAINT GREEN (-8720 3082);
DISPLAY INVISIBLE (-8720 3082);
FORCEPROP 1 LAST HDL_POWER GND
J 0
(-8675 3275);
DISPLAY 0.723404 (-8675 3275);
PAINT GREEN (-8675 3275);
DISPLAY INVISIBLE (-8675 3275);
FORCEPROP 1 LAST PATH I186
J 0
(-8600 3125);
DISPLAY 0.872340 (-8600 3125);
PAINT AQUA (-8600 3125);
DISPLAY INVISIBLE (-8600 3125);
FORCEADD OFFPAGE..6
(-9100 2275);
FORCEPROP 2 LAST $XR4 102 
J 0
(-9439 2203);
DISPLAY 0.638298 (-9439 2203);
PAINT MONO (-9439 2203);
FORCEPROP 2 LAST $XR3 101 
J 0
(-9439 2311);
DISPLAY 0.638298 (-9439 2311);
PAINT MONO (-9439 2311);
FORCEPROP 2 LAST $XR2 100 
J 0
(-9439 2239);
DISPLAY 0.638298 (-9439 2239);
PAINT MONO (-9439 2239);
FORCEPROP 2 LAST $XR1 99 
J 0
(-9439 2275);
DISPLAY 0.638298 (-9439 2275);
PAINT MONO (-9439 2275);
FORCEPROP 2 LAST $XR0 98 
J 0
(-9349 2275);
DISPLAY 0.638298 (-9349 2275);
PAINT MONO (-9349 2275);
FORCEPROP 2 LAST CDS_LIB mstr_standard
J 0
(-9100 2275);
DISPLAY 0.808511 (-9100 2275);
DISPLAY INVISIBLE (-9100 2275);
FORCEPROP 1 LAST OFFPAGE TRUE
J 0
(-8775 2150);
DISPLAY 0.872340 (-8775 2150);
PAINT GREEN (-8775 2150);
DISPLAY INVISIBLE (-8775 2150);
FORCEPROP 1 LAST COMMENT_BODY TRUE
J 0
(-9000 2200);
DISPLAY 0.872340 (-9000 2200);
PAINT GREEN (-9000 2200);
DISPLAY INVISIBLE (-9000 2200);
FORCEPROP 2 LAST PATH I187
J 0
(-9050 2350);
DISPLAY 1.021277 (-9050 2350);
DISPLAY INVISIBLE (-9050 2350);
FORCEADD Q_RES..1
R 2
(-8600 2275);
FORCEPROP 1 LAST LOCATION R1183
J 2
(-8575 2300);
DISPLAY 0.489362 (-8575 2300);
PAINT SKYBLUE (-8575 2300);
FORCEPROP 0 LAST $SEC 1
J 0
(-8575 2350);
DISPLAY 0.680851 (-8575 2350);
PAINT MONO (-8575 2350);
DISPLAY INVISIBLE (-8575 2350);
FORCEPROP 0 LAST CDS_SEC 1
J 0
(-8575 2350);
DISPLAY 1.021277 (-8575 2350);
DISPLAY INVISIBLE (-8575 2350);
FORCEPROP 1 LASTPIN (-8500 2275) $PN 1
J 2
(-8512 2287);
DISPLAY 0.489362 (-8512 2287);
PAINT MONO (-8512 2287);
FORCEPROP 1 LASTPIN (-8700 2275) $PN 2
J 2
(-8662 2287);
DISPLAY 0.489362 (-8662 2287);
PAINT MONO (-8662 2287);
FORCEPROP 1 LAST VALUE 1K
J 0
(-8600 2225);
DISPLAY 0.489362 (-8600 2225);
PAINT SKYBLUE (-8600 2225);
FORCEPROP 1 LAST TOLERANCE 1%
J 2
(-8475 2250);
DISPLAY 0.489362 (-8475 2250);
PAINT SKYBLUE (-8475 2250);
DISPLAY INVISIBLE (-8475 2250);
FORCEPROP 2 LAST BOM_COST MEM
J 0
(-8625 2425);
DISPLAY 0.744681 (-8625 2425);
PAINT WHITE (-8625 2425);
DISPLAY INVISIBLE (-8625 2425);
FORCEPROP 2 LAST CDS_LIB pure_quanta
J 0
(-8600 2275);
DISPLAY INVISIBLE (-8600 2275);
FORCEPROP 1 LAST WATTAGE 1/16W
J 0
(-8525 2200);
DISPLAY 0.489362 (-8525 2200);
PAINT SKYBLUE (-8525 2200);
DISPLAY INVISIBLE (-8525 2200);
FORCEPROP 1 LAST MATERIAL CHIP
J 0
(-8775 2250);
DISPLAY 0.489362 (-8775 2250);
PAINT SKYBLUE (-8775 2250);
DISPLAY INVISIBLE (-8775 2250);
FORCEPROP 1 LAST PACK_TYPE 0402LF
J 0
(-8775 2200);
DISPLAY 0.489362 (-8775 2200);
PAINT SKYBLUE (-8775 2200);
DISPLAY INVISIBLE (-8775 2200);
FORCEPROP 2 LAST ROOM 
J 0
(-8625 2375);
DISPLAY 0.744681 (-8625 2375);
PAINT RED (-8625 2375);
DISPLAY INVISIBLE (-8625 2375);
FORCEPROP 1 LAST PATH I188
J 2
(-8550 2425);
DISPLAY 0.978723 (-8550 2425);
PAINT WHITE (-8550 2425);
DISPLAY INVISIBLE (-8550 2425);
FORCEPROP 1 LAST PART_NUMBER CS21002FB06
J 0
(-8700 2325);
DISPLAY 0.489362 (-8700 2325);
PAINT SKYBLUE (-8700 2325);
DISPLAY INVISIBLE (-8700 2325);
FORCEADD VCC_CORE..1
(-8475 2600);
FORCEPROP 3 LASTPIN (-8475 2550) SIG_NAME P3V3\g
J 0
(-8465 2560);
DISPLAY 0.659574 (-8465 2560);
PAINT MONO (-8465 2560);
DISPLAY INVISIBLE (-8465 2560);
FORCEPROP 1 LAST HDL_POWER P3V3
J 1
(-8475 2650);
DISPLAY 0.489362 (-8475 2650);
PAINT GREEN (-8475 2650);
FORCEPROP 2 LAST CDS_LIB mstr_symbols
J 0
(-8475 2600);
DISPLAY INVISIBLE (-8475 2600);
FORCEPROP 0 LAST VOLTAGE 3.3
J 0
(-8750 2750);
DISPLAY 1.021277 (-8750 2750);
PAINT SKYBLUE (-8750 2750);
DISPLAY INVISIBLE (-8750 2750);
FORCEPROP 2 LAST ROOM PVCCINFAON_CPU0_CTRL
J 0
(-8475 2700);
DISPLAY 0.808511 (-8475 2700);
PAINT RED (-8475 2700);
DISPLAY INVISIBLE (-8475 2700);
FORCEPROP 1 LAST PATH I189
J 0
(-8425 2625);
DISPLAY 0.872340 (-8425 2625);
PAINT AQUA (-8425 2625);
DISPLAY INVISIBLE (-8425 2625);
FORCEADD OFFPAGE..1
(-8425 4725);
FORCEPROP 2 LAST $XR0 42 
J 0
(-8646 4725);
DISPLAY 0.638298 (-8646 4725);
PAINT MONO (-8646 4725);
FORCEPROP 2 LAST CDS_LIB mstr_standard
J 0
(-8425 4725);
DISPLAY 0.723404 (-8425 4725);
PAINT MONO (-8425 4725);
DISPLAY INVISIBLE (-8425 4725);
FORCEPROP 1 LAST OFFPAGE TRUE
J 0
(-8100 4600);
DISPLAY 0.872340 (-8100 4600);
PAINT GREEN (-8100 4600);
DISPLAY INVISIBLE (-8100 4600);
FORCEPROP 1 LAST COMMENT_BODY TRUE
J 0
(-8300 4625);
DISPLAY 0.872340 (-8300 4625);
PAINT GREEN (-8300 4625);
DISPLAY INVISIBLE (-8300 4625);
FORCEPROP 2 LAST PATH I19
J 0
(-8675 4775);
DISPLAY 1.021277 (-8675 4775);
DISPLAY INVISIBLE (-8675 4775);
FORCEADD Q_RES..2
(-8475 2425);
FORCEPROP 1 LAST LOCATION R108
J 0
(-8430 2550);
DISPLAY 0.489362 (-8430 2550);
PAINT SKYBLUE (-8430 2550);
FORCEPROP 0 LAST $SEC 1
J 0
(-8425 2600);
DISPLAY 0.680851 (-8425 2600);
PAINT MONO (-8425 2600);
DISPLAY INVISIBLE (-8425 2600);
FORCEPROP 0 LAST CDS_SEC 1
J 0
(-8425 2600);
DISPLAY 1.021277 (-8425 2600);
DISPLAY INVISIBLE (-8425 2600);
FORCEPROP 1 LASTPIN (-8475 2525) $PN 1
J 0
(-8470 2487);
DISPLAY 0.489362 (-8470 2487);
PAINT MONO (-8470 2487);
FORCEPROP 1 LASTPIN (-8475 2325) $PN 2
J 0
(-8470 2335);
DISPLAY 0.489362 (-8470 2335);
PAINT MONO (-8470 2335);
FORCEPROP 1 LAST PACK_TYPE 0402LF
J 0
(-8425 2375);
DISPLAY 0.489362 (-8425 2375);
PAINT SKYBLUE (-8425 2375);
FORCEPROP 1 LAST MATERIAL EMPTY
J 0
(-8425 2425);
DISPLAY 0.489362 (-8425 2425);
PAINT RED (-8425 2425);
FORCEPROP 1 LAST WATTAGE 1/16W
J 0
(-8425 2450);
DISPLAY 0.489362 (-8425 2450);
PAINT SKYBLUE (-8425 2450);
FORCEPROP 1 LAST TOLERANCE 1%
J 0
(-8425 2475);
DISPLAY 0.489362 (-8425 2475);
PAINT SKYBLUE (-8425 2475);
FORCEPROP 1 LAST VALUE 1K
J 0
(-8430 2500);
DISPLAY 0.489362 (-8430 2500);
PAINT SKYBLUE (-8430 2500);
FORCEPROP 2 LAST CDS_LIB pure_quanta
J 2
(-8475 2425);
DISPLAY INVISIBLE (-8475 2425);
FORCEPROP 2 LAST BOM_COST MEM
J 0
(-8425 2600);
DISPLAY 0.808511 (-8425 2600);
DISPLAY INVISIBLE (-8425 2600);
FORCEPROP 2 LAST ROOM 
J 0
(-8425 2650);
DISPLAY 0.808511 (-8425 2650);
PAINT RED (-8425 2650);
DISPLAY INVISIBLE (-8425 2650);
FORCEPROP 1 LAST PATH I190
J 0
(-8425 2600);
DISPLAY 0.978723 (-8425 2600);
PAINT WHITE (-8425 2600);
DISPLAY INVISIBLE (-8425 2600);
FORCEPROP 1 LAST PART_NUMBER CS21002FB06
J 0
(-8425 2400);
DISPLAY 0.489362 (-8425 2400);
PAINT SKYBLUE (-8425 2400);
DISPLAY INVISIBLE (-8425 2400);
FORCEADD TAP..1
(-3500 4000);
FORCEPROP 3 LASTPIN (-3550 4000) SIG_NAME M_F_CPU1_SA_DQS_DP<2>
J 0
(-3540 4010);
DISPLAY 0.659574 (-3540 4010);
PAINT MONO (-3540 4010);
DISPLAY INVISIBLE (-3540 4010);
FORCEPROP 1 LASTPIN (-3550 4000) BN 2
J 0
(-3562 4008);
DISPLAY 0.489362 (-3562 4008);
PAINT GREEN (-3562 4008);
FORCEPROP 2 LAST CDS_LIB mstr_standard
J 0
(-3500 4000);
DISPLAY 0.723404 (-3500 4000);
PAINT MONO (-3500 4000);
DISPLAY INVISIBLE (-3500 4000);
FORCEPROP 1 LAST BODY_TYPE PLUMBING
J 0
(-3500 4050);
DISPLAY 0.872340 (-3500 4050);
PAINT GREEN (-3500 4050);
DISPLAY INVISIBLE (-3500 4050);
FORCEPROP 1 LAST HDL_TAP TRUE
J 0
(-3175 3875);
DISPLAY 0.872340 (-3175 3875);
DISPLAY INVISIBLE (-3175 3875);
FORCEPROP 1 LAST PATH I191
J 0
(-3502 4000);
DISPLAY 0.872340 (-3502 4000);
PAINT GREEN (-3502 4000);
DISPLAY INVISIBLE (-3502 4000);
FORCEADD TAP..1
(-3500 4200);
FORCEPROP 3 LASTPIN (-3550 4200) SIG_NAME M_F_CPU1_SA_DQS_DP<4>
J 0
(-3540 4210);
DISPLAY 0.659574 (-3540 4210);
PAINT MONO (-3540 4210);
DISPLAY INVISIBLE (-3540 4210);
FORCEPROP 1 LASTPIN (-3550 4200) BN 4
J 0
(-3562 4208);
DISPLAY 0.489362 (-3562 4208);
PAINT GREEN (-3562 4208);
FORCEPROP 2 LAST CDS_LIB mstr_standard
J 0
(-3500 4200);
DISPLAY 0.723404 (-3500 4200);
PAINT MONO (-3500 4200);
DISPLAY INVISIBLE (-3500 4200);
FORCEPROP 1 LAST BODY_TYPE PLUMBING
J 0
(-3500 4250);
DISPLAY 0.872340 (-3500 4250);
PAINT GREEN (-3500 4250);
DISPLAY INVISIBLE (-3500 4250);
FORCEPROP 1 LAST HDL_TAP TRUE
J 0
(-3175 4075);
DISPLAY 0.872340 (-3175 4075);
DISPLAY INVISIBLE (-3175 4075);
FORCEPROP 1 LAST PATH I193
J 0
(-3502 4200);
DISPLAY 0.872340 (-3502 4200);
PAINT GREEN (-3502 4200);
DISPLAY INVISIBLE (-3502 4200);
FORCEADD OFFPAGE..2
(-2500 4700);
FORCEPROP 2 LAST $XR0 42 
J 0
(-2311 4700);
DISPLAY 0.638298 (-2311 4700);
PAINT MONO (-2311 4700);
FORCEPROP 2 LAST CDS_LIB mstr_standard
J 0
(-2500 4700);
DISPLAY 0.723404 (-2500 4700);
PAINT MONO (-2500 4700);
DISPLAY INVISIBLE (-2500 4700);
FORCEPROP 1 LAST OFFPAGE TRUE
J 0
(-2175 4575);
DISPLAY 0.723404 (-2175 4575);
PAINT GREEN (-2175 4575);
DISPLAY INVISIBLE (-2175 4575);
FORCEPROP 1 LAST COMMENT_BODY TRUE
J 0
(-2545 4605);
DISPLAY 0.872340 (-2545 4605);
PAINT GREEN (-2545 4605);
DISPLAY INVISIBLE (-2545 4605);
FORCEPROP 2 LAST PATH I194
J 0
(-2300 4750);
DISPLAY 0.680851 (-2300 4750);
DISPLAY INVISIBLE (-2300 4750);
FORCEADD OFFPAGE..2
(-2500 4750);
FORCEPROP 2 LAST $XR0 42 
J 0
(-2311 4750);
DISPLAY 0.638298 (-2311 4750);
PAINT MONO (-2311 4750);
FORCEPROP 2 LAST CDS_LIB mstr_standard
J 0
(-2500 4750);
DISPLAY 0.723404 (-2500 4750);
PAINT MONO (-2500 4750);
DISPLAY INVISIBLE (-2500 4750);
FORCEPROP 1 LAST OFFPAGE TRUE
J 0
(-2175 4625);
DISPLAY 0.723404 (-2175 4625);
PAINT GREEN (-2175 4625);
DISPLAY INVISIBLE (-2175 4625);
FORCEPROP 1 LAST COMMENT_BODY TRUE
J 0
(-2545 4655);
DISPLAY 0.872340 (-2545 4655);
PAINT GREEN (-2545 4655);
DISPLAY INVISIBLE (-2545 4655);
FORCEPROP 2 LAST PATH I195
J 0
(-2300 4800);
DISPLAY 0.680851 (-2300 4800);
DISPLAY INVISIBLE (-2300 4800);
FORCEADD OFFPAGE..2
(-2500 3650);
FORCEPROP 2 LAST $XR0 42 
J 0
(-2311 3650);
DISPLAY 0.638298 (-2311 3650);
PAINT MONO (-2311 3650);
FORCEPROP 2 LAST CDS_LIB mstr_standard
J 0
(-2500 3650);
DISPLAY 0.723404 (-2500 3650);
PAINT MONO (-2500 3650);
DISPLAY INVISIBLE (-2500 3650);
FORCEPROP 1 LAST OFFPAGE TRUE
J 0
(-2175 3525);
DISPLAY 0.723404 (-2175 3525);
PAINT GREEN (-2175 3525);
DISPLAY INVISIBLE (-2175 3525);
FORCEPROP 1 LAST COMMENT_BODY TRUE
J 0
(-2545 3555);
DISPLAY 0.872340 (-2545 3555);
PAINT GREEN (-2545 3555);
DISPLAY INVISIBLE (-2545 3555);
FORCEPROP 2 LAST PATH I196
J 0
(-2300 3700);
DISPLAY 0.680851 (-2300 3700);
DISPLAY INVISIBLE (-2300 3700);
FORCEADD OFFPAGE..2
(-2500 3700);
FORCEPROP 2 LAST $XR0 42 
J 0
(-2311 3700);
DISPLAY 0.638298 (-2311 3700);
PAINT MONO (-2311 3700);
FORCEPROP 2 LAST CDS_LIB mstr_standard
J 0
(-2500 3700);
DISPLAY 0.723404 (-2500 3700);
PAINT MONO (-2500 3700);
DISPLAY INVISIBLE (-2500 3700);
FORCEPROP 1 LAST OFFPAGE TRUE
J 0
(-2175 3575);
DISPLAY 0.723404 (-2175 3575);
PAINT GREEN (-2175 3575);
DISPLAY INVISIBLE (-2175 3575);
FORCEPROP 1 LAST COMMENT_BODY TRUE
J 0
(-2545 3605);
DISPLAY 0.872340 (-2545 3605);
PAINT GREEN (-2545 3605);
DISPLAY INVISIBLE (-2545 3605);
FORCEPROP 2 LAST PATH I197
J 0
(-2300 3750);
DISPLAY 0.680851 (-2300 3750);
DISPLAY INVISIBLE (-2300 3750);
FORCEADD TAP..1
(-3300 4650);
FORCEPROP 3 LASTPIN (-3350 4650) SIG_NAME M_F_CPU1_SA_DQS_DN<9>
J 0
(-3340 4660);
DISPLAY 0.659574 (-3340 4660);
PAINT MONO (-3340 4660);
DISPLAY INVISIBLE (-3340 4660);
FORCEPROP 1 LASTPIN (-3350 4650) BN 9
J 0
(-3362 4658);
DISPLAY 0.489362 (-3362 4658);
PAINT GREEN (-3362 4658);
FORCEPROP 2 LAST CDS_LIB mstr_standard
J 0
(-3300 4650);
DISPLAY 0.723404 (-3300 4650);
PAINT MONO (-3300 4650);
DISPLAY INVISIBLE (-3300 4650);
FORCEPROP 1 LAST BODY_TYPE PLUMBING
J 0
(-3300 4700);
DISPLAY 0.872340 (-3300 4700);
PAINT GREEN (-3300 4700);
DISPLAY INVISIBLE (-3300 4700);
FORCEPROP 1 LAST HDL_TAP TRUE
J 0
(-2975 4525);
DISPLAY 0.872340 (-2975 4525);
DISPLAY INVISIBLE (-2975 4525);
FORCEPROP 1 LAST PATH I198
J 0
(-3302 4650);
DISPLAY 0.872340 (-3302 4650);
PAINT GREEN (-3302 4650);
DISPLAY INVISIBLE (-3302 4650);
FORCEADD TAP..1
(-3300 4550);
FORCEPROP 3 LASTPIN (-3350 4550) SIG_NAME M_F_CPU1_SA_DQS_DN<8>
J 0
(-3340 4560);
DISPLAY 0.659574 (-3340 4560);
PAINT MONO (-3340 4560);
DISPLAY INVISIBLE (-3340 4560);
FORCEPROP 1 LASTPIN (-3350 4550) BN 8
J 0
(-3362 4558);
DISPLAY 0.489362 (-3362 4558);
PAINT GREEN (-3362 4558);
FORCEPROP 2 LAST CDS_LIB mstr_standard
J 0
(-3300 4550);
DISPLAY 0.723404 (-3300 4550);
PAINT MONO (-3300 4550);
DISPLAY INVISIBLE (-3300 4550);
FORCEPROP 1 LAST BODY_TYPE PLUMBING
J 0
(-3300 4600);
DISPLAY 0.872340 (-3300 4600);
PAINT GREEN (-3300 4600);
DISPLAY INVISIBLE (-3300 4600);
FORCEPROP 1 LAST HDL_TAP TRUE
J 0
(-2975 4425);
DISPLAY 0.872340 (-2975 4425);
DISPLAY INVISIBLE (-2975 4425);
FORCEPROP 1 LAST PATH I199
J 0
(-3302 4550);
DISPLAY 0.872340 (-3302 4550);
PAINT GREEN (-3302 4550);
DISPLAY INVISIBLE (-3302 4550);
FORCEADD OFFPAGE..5
(-8425 2075);
FORCEPROP 2 LAST $XR0 42 
J 0
(-8649 2075);
DISPLAY 0.638298 (-8649 2075);
PAINT MONO (-8649 2075);
FORCEPROP 2 LAST CDS_LIB mstr_standard
J 0
(-8425 2075);
DISPLAY 0.808511 (-8425 2075);
DISPLAY INVISIBLE (-8425 2075);
FORCEPROP 1 LAST OFFPAGE TRUE
J 0
(-8100 1950);
DISPLAY 0.872340 (-8100 1950);
PAINT GREEN (-8100 1950);
DISPLAY INVISIBLE (-8100 1950);
FORCEPROP 1 LAST COMMENT_BODY TRUE
J 0
(-8325 2000);
DISPLAY 0.872340 (-8325 2000);
PAINT GREEN (-8325 2000);
DISPLAY INVISIBLE (-8325 2000);
FORCEPROP 2 LAST PATH I2
J 0
(-8625 2125);
DISPLAY 1.021277 (-8625 2125);
DISPLAY INVISIBLE (-8625 2125);
FORCEADD OFFPAGE..1
(-8425 5575);
FORCEPROP 2 LAST $XR0 42 
J 0
(-8646 5575);
DISPLAY 0.638298 (-8646 5575);
PAINT MONO (-8646 5575);
FORCEPROP 2 LAST CDS_LIB mstr_standard
J 0
(-8425 5575);
DISPLAY 0.723404 (-8425 5575);
PAINT MONO (-8425 5575);
DISPLAY INVISIBLE (-8425 5575);
FORCEPROP 1 LAST OFFPAGE TRUE
J 0
(-8100 5450);
DISPLAY 0.872340 (-8100 5450);
PAINT GREEN (-8100 5450);
DISPLAY INVISIBLE (-8100 5450);
FORCEPROP 1 LAST COMMENT_BODY TRUE
J 0
(-8300 5475);
DISPLAY 0.872340 (-8300 5475);
PAINT GREEN (-8300 5475);
DISPLAY INVISIBLE (-8300 5475);
FORCEPROP 2 LAST PATH I20
J 0
(-8675 5625);
DISPLAY 1.021277 (-8675 5625);
DISPLAY INVISIBLE (-8675 5625);
FORCEADD TAP..1
(-3300 4450);
FORCEPROP 3 LASTPIN (-3350 4450) SIG_NAME M_F_CPU1_SA_DQS_DN<7>
J 0
(-3340 4460);
DISPLAY 0.659574 (-3340 4460);
PAINT MONO (-3340 4460);
DISPLAY INVISIBLE (-3340 4460);
FORCEPROP 1 LASTPIN (-3350 4450) BN 7
J 0
(-3362 4458);
DISPLAY 0.489362 (-3362 4458);
PAINT GREEN (-3362 4458);
FORCEPROP 2 LAST CDS_LIB mstr_standard
J 0
(-3300 4450);
DISPLAY 0.723404 (-3300 4450);
PAINT MONO (-3300 4450);
DISPLAY INVISIBLE (-3300 4450);
FORCEPROP 1 LAST BODY_TYPE PLUMBING
J 0
(-3300 4500);
DISPLAY 0.872340 (-3300 4500);
PAINT GREEN (-3300 4500);
DISPLAY INVISIBLE (-3300 4500);
FORCEPROP 1 LAST HDL_TAP TRUE
J 0
(-2975 4325);
DISPLAY 0.872340 (-2975 4325);
DISPLAY INVISIBLE (-2975 4325);
FORCEPROP 1 LAST PATH I200
J 0
(-3302 4450);
DISPLAY 0.872340 (-3302 4450);
PAINT GREEN (-3302 4450);
DISPLAY INVISIBLE (-3302 4450);
FORCEADD TAP..1
(-3500 4700);
FORCEPROP 3 LASTPIN (-3550 4700) SIG_NAME M_F_CPU1_SA_DQS_DP<9>
J 0
(-3540 4710);
DISPLAY 0.659574 (-3540 4710);
PAINT MONO (-3540 4710);
DISPLAY INVISIBLE (-3540 4710);
FORCEPROP 1 LASTPIN (-3550 4700) BN 9
J 0
(-3562 4708);
DISPLAY 0.489362 (-3562 4708);
PAINT GREEN (-3562 4708);
FORCEPROP 2 LAST CDS_LIB mstr_standard
J 0
(-3500 4700);
DISPLAY 0.723404 (-3500 4700);
PAINT MONO (-3500 4700);
DISPLAY INVISIBLE (-3500 4700);
FORCEPROP 1 LAST BODY_TYPE PLUMBING
J 0
(-3500 4750);
DISPLAY 0.872340 (-3500 4750);
PAINT GREEN (-3500 4750);
DISPLAY INVISIBLE (-3500 4750);
FORCEPROP 1 LAST HDL_TAP TRUE
J 0
(-3175 4575);
DISPLAY 0.872340 (-3175 4575);
DISPLAY INVISIBLE (-3175 4575);
FORCEPROP 1 LAST PATH I201
J 0
(-3502 4700);
DISPLAY 0.872340 (-3502 4700);
PAINT GREEN (-3502 4700);
DISPLAY INVISIBLE (-3502 4700);
FORCEADD TAP..1
(-3500 4600);
FORCEPROP 3 LASTPIN (-3550 4600) SIG_NAME M_F_CPU1_SA_DQS_DP<8>
J 0
(-3540 4610);
DISPLAY 0.659574 (-3540 4610);
PAINT MONO (-3540 4610);
DISPLAY INVISIBLE (-3540 4610);
FORCEPROP 1 LASTPIN (-3550 4600) BN 8
J 0
(-3562 4608);
DISPLAY 0.489362 (-3562 4608);
PAINT GREEN (-3562 4608);
FORCEPROP 2 LAST CDS_LIB mstr_standard
J 0
(-3500 4600);
DISPLAY 0.723404 (-3500 4600);
PAINT MONO (-3500 4600);
DISPLAY INVISIBLE (-3500 4600);
FORCEPROP 1 LAST BODY_TYPE PLUMBING
J 0
(-3500 4650);
DISPLAY 0.872340 (-3500 4650);
PAINT GREEN (-3500 4650);
DISPLAY INVISIBLE (-3500 4650);
FORCEPROP 1 LAST HDL_TAP TRUE
J 0
(-3175 4475);
DISPLAY 0.872340 (-3175 4475);
DISPLAY INVISIBLE (-3175 4475);
FORCEPROP 1 LAST PATH I202
J 0
(-3502 4600);
DISPLAY 0.872340 (-3502 4600);
PAINT GREEN (-3502 4600);
DISPLAY INVISIBLE (-3502 4600);
FORCEADD TAP..1
(-3500 4400);
FORCEPROP 3 LASTPIN (-3550 4400) SIG_NAME M_F_CPU1_SA_DQS_DP<6>
J 0
(-3540 4410);
DISPLAY 0.659574 (-3540 4410);
PAINT MONO (-3540 4410);
DISPLAY INVISIBLE (-3540 4410);
FORCEPROP 1 LASTPIN (-3550 4400) BN 6
J 0
(-3562 4408);
DISPLAY 0.489362 (-3562 4408);
PAINT GREEN (-3562 4408);
FORCEPROP 2 LAST CDS_LIB mstr_standard
J 0
(-3500 4400);
DISPLAY 0.723404 (-3500 4400);
PAINT MONO (-3500 4400);
DISPLAY INVISIBLE (-3500 4400);
FORCEPROP 1 LAST BODY_TYPE PLUMBING
J 0
(-3500 4450);
DISPLAY 0.872340 (-3500 4450);
PAINT GREEN (-3500 4450);
DISPLAY INVISIBLE (-3500 4450);
FORCEPROP 1 LAST HDL_TAP TRUE
J 0
(-3175 4275);
DISPLAY 0.872340 (-3175 4275);
DISPLAY INVISIBLE (-3175 4275);
FORCEPROP 1 LAST PATH I203
J 0
(-3502 4400);
DISPLAY 0.872340 (-3502 4400);
PAINT GREEN (-3502 4400);
DISPLAY INVISIBLE (-3502 4400);
FORCEADD TAP..1
(-3500 4500);
FORCEPROP 3 LASTPIN (-3550 4500) SIG_NAME M_F_CPU1_SA_DQS_DP<7>
J 0
(-3540 4510);
DISPLAY 0.659574 (-3540 4510);
PAINT MONO (-3540 4510);
DISPLAY INVISIBLE (-3540 4510);
FORCEPROP 1 LASTPIN (-3550 4500) BN 7
J 0
(-3562 4508);
DISPLAY 0.489362 (-3562 4508);
PAINT GREEN (-3562 4508);
FORCEPROP 2 LAST CDS_LIB mstr_standard
J 0
(-3500 4500);
DISPLAY 0.723404 (-3500 4500);
PAINT MONO (-3500 4500);
DISPLAY INVISIBLE (-3500 4500);
FORCEPROP 1 LAST BODY_TYPE PLUMBING
J 0
(-3500 4550);
DISPLAY 0.872340 (-3500 4550);
PAINT GREEN (-3500 4550);
DISPLAY INVISIBLE (-3500 4550);
FORCEPROP 1 LAST HDL_TAP TRUE
J 0
(-3175 4375);
DISPLAY 0.872340 (-3175 4375);
DISPLAY INVISIBLE (-3175 4375);
FORCEPROP 1 LAST PATH I204
J 0
(-3502 4500);
DISPLAY 0.872340 (-3502 4500);
PAINT GREEN (-3502 4500);
DISPLAY INVISIBLE (-3502 4500);
FORCEADD TAP..1
(-3300 4350);
FORCEPROP 3 LASTPIN (-3350 4350) SIG_NAME M_F_CPU1_SA_DQS_DN<6>
J 0
(-3340 4360);
DISPLAY 0.659574 (-3340 4360);
PAINT MONO (-3340 4360);
DISPLAY INVISIBLE (-3340 4360);
FORCEPROP 1 LASTPIN (-3350 4350) BN 6
J 0
(-3362 4358);
DISPLAY 0.489362 (-3362 4358);
PAINT GREEN (-3362 4358);
FORCEPROP 2 LAST CDS_LIB mstr_standard
J 0
(-3300 4350);
DISPLAY 0.723404 (-3300 4350);
PAINT MONO (-3300 4350);
DISPLAY INVISIBLE (-3300 4350);
FORCEPROP 1 LAST BODY_TYPE PLUMBING
J 0
(-3300 4400);
DISPLAY 0.872340 (-3300 4400);
PAINT GREEN (-3300 4400);
DISPLAY INVISIBLE (-3300 4400);
FORCEPROP 1 LAST HDL_TAP TRUE
J 0
(-2975 4225);
DISPLAY 0.872340 (-2975 4225);
DISPLAY INVISIBLE (-2975 4225);
FORCEPROP 1 LAST PATH I205
J 0
(-3302 4350);
DISPLAY 0.872340 (-3302 4350);
PAINT GREEN (-3302 4350);
DISPLAY INVISIBLE (-3302 4350);
FORCEADD TAP..1
(-3300 4250);
FORCEPROP 3 LASTPIN (-3350 4250) SIG_NAME M_F_CPU1_SA_DQS_DN<5>
J 0
(-3340 4260);
DISPLAY 0.659574 (-3340 4260);
PAINT MONO (-3340 4260);
DISPLAY INVISIBLE (-3340 4260);
FORCEPROP 1 LASTPIN (-3350 4250) BN 5
J 0
(-3362 4258);
DISPLAY 0.489362 (-3362 4258);
PAINT GREEN (-3362 4258);
FORCEPROP 2 LAST CDS_LIB mstr_standard
J 0
(-3300 4250);
DISPLAY 0.723404 (-3300 4250);
PAINT MONO (-3300 4250);
DISPLAY INVISIBLE (-3300 4250);
FORCEPROP 1 LAST BODY_TYPE PLUMBING
J 0
(-3300 4300);
DISPLAY 0.872340 (-3300 4300);
PAINT GREEN (-3300 4300);
DISPLAY INVISIBLE (-3300 4300);
FORCEPROP 1 LAST HDL_TAP TRUE
J 0
(-2975 4125);
DISPLAY 0.872340 (-2975 4125);
DISPLAY INVISIBLE (-2975 4125);
FORCEPROP 1 LAST PATH I206
J 0
(-3302 4250);
DISPLAY 0.872340 (-3302 4250);
PAINT GREEN (-3302 4250);
DISPLAY INVISIBLE (-3302 4250);
FORCEADD TAP..1
(-3300 4150);
FORCEPROP 3 LASTPIN (-3350 4150) SIG_NAME M_F_CPU1_SA_DQS_DN<4>
J 0
(-3340 4160);
DISPLAY 0.659574 (-3340 4160);
PAINT MONO (-3340 4160);
DISPLAY INVISIBLE (-3340 4160);
FORCEPROP 1 LASTPIN (-3350 4150) BN 4
J 0
(-3362 4158);
DISPLAY 0.489362 (-3362 4158);
PAINT GREEN (-3362 4158);
FORCEPROP 2 LAST CDS_LIB mstr_standard
J 0
(-3300 4150);
DISPLAY 0.723404 (-3300 4150);
PAINT MONO (-3300 4150);
DISPLAY INVISIBLE (-3300 4150);
FORCEPROP 1 LAST BODY_TYPE PLUMBING
J 0
(-3300 4200);
DISPLAY 0.872340 (-3300 4200);
PAINT GREEN (-3300 4200);
DISPLAY INVISIBLE (-3300 4200);
FORCEPROP 1 LAST HDL_TAP TRUE
J 0
(-2975 4025);
DISPLAY 0.872340 (-2975 4025);
DISPLAY INVISIBLE (-2975 4025);
FORCEPROP 1 LAST PATH I207
J 0
(-3302 4150);
DISPLAY 0.872340 (-3302 4150);
PAINT GREEN (-3302 4150);
DISPLAY INVISIBLE (-3302 4150);
FORCEADD TAP..1
(-3300 4050);
FORCEPROP 3 LASTPIN (-3350 4050) SIG_NAME M_F_CPU1_SA_DQS_DN<3>
J 0
(-3340 4060);
DISPLAY 0.659574 (-3340 4060);
PAINT MONO (-3340 4060);
DISPLAY INVISIBLE (-3340 4060);
FORCEPROP 1 LASTPIN (-3350 4050) BN 3
J 0
(-3362 4058);
DISPLAY 0.489362 (-3362 4058);
PAINT GREEN (-3362 4058);
FORCEPROP 2 LAST CDS_LIB mstr_standard
J 0
(-3300 4050);
DISPLAY 0.723404 (-3300 4050);
PAINT MONO (-3300 4050);
DISPLAY INVISIBLE (-3300 4050);
FORCEPROP 1 LAST BODY_TYPE PLUMBING
J 0
(-3300 4100);
DISPLAY 0.872340 (-3300 4100);
PAINT GREEN (-3300 4100);
DISPLAY INVISIBLE (-3300 4100);
FORCEPROP 1 LAST HDL_TAP TRUE
J 0
(-2975 3925);
DISPLAY 0.872340 (-2975 3925);
DISPLAY INVISIBLE (-2975 3925);
FORCEPROP 1 LAST PATH I208
J 0
(-3302 4050);
DISPLAY 0.872340 (-3302 4050);
PAINT GREEN (-3302 4050);
DISPLAY INVISIBLE (-3302 4050);
FORCEADD TAP..1
(-3300 3950);
FORCEPROP 3 LASTPIN (-3350 3950) SIG_NAME M_F_CPU1_SA_DQS_DN<2>
J 0
(-3340 3960);
DISPLAY 0.659574 (-3340 3960);
PAINT MONO (-3340 3960);
DISPLAY INVISIBLE (-3340 3960);
FORCEPROP 1 LASTPIN (-3350 3950) BN 2
J 0
(-3362 3958);
DISPLAY 0.489362 (-3362 3958);
PAINT GREEN (-3362 3958);
FORCEPROP 2 LAST CDS_LIB mstr_standard
J 0
(-3300 3950);
DISPLAY 0.723404 (-3300 3950);
PAINT MONO (-3300 3950);
DISPLAY INVISIBLE (-3300 3950);
FORCEPROP 1 LAST BODY_TYPE PLUMBING
J 0
(-3300 4000);
DISPLAY 0.872340 (-3300 4000);
PAINT GREEN (-3300 4000);
DISPLAY INVISIBLE (-3300 4000);
FORCEPROP 1 LAST HDL_TAP TRUE
J 0
(-2975 3825);
DISPLAY 0.872340 (-2975 3825);
DISPLAY INVISIBLE (-2975 3825);
FORCEPROP 1 LAST PATH I209
J 0
(-3302 3950);
DISPLAY 0.872340 (-3302 3950);
PAINT GREEN (-3302 3950);
DISPLAY INVISIBLE (-3302 3950);
FORCEADD OFFPAGE..1
(-8425 5175);
FORCEPROP 2 LAST $XR0 42 
J 0
(-8646 5175);
DISPLAY 0.638298 (-8646 5175);
PAINT MONO (-8646 5175);
FORCEPROP 2 LAST CDS_LIB mstr_standard
J 0
(-8425 5175);
DISPLAY 0.723404 (-8425 5175);
PAINT MONO (-8425 5175);
DISPLAY INVISIBLE (-8425 5175);
FORCEPROP 1 LAST OFFPAGE TRUE
J 0
(-8100 5050);
DISPLAY 0.872340 (-8100 5050);
PAINT GREEN (-8100 5050);
DISPLAY INVISIBLE (-8100 5050);
FORCEPROP 1 LAST COMMENT_BODY TRUE
J 0
(-8300 5075);
DISPLAY 0.872340 (-8300 5075);
PAINT GREEN (-8300 5075);
DISPLAY INVISIBLE (-8300 5075);
FORCEPROP 2 LAST PATH I21
J 0
(-8675 5225);
DISPLAY 1.021277 (-8675 5225);
DISPLAY INVISIBLE (-8675 5225);
FORCEADD TAP..1
(-3500 4300);
FORCEPROP 3 LASTPIN (-3550 4300) SIG_NAME M_F_CPU1_SA_DQS_DP<5>
J 0
(-3540 4310);
DISPLAY 0.659574 (-3540 4310);
PAINT MONO (-3540 4310);
DISPLAY INVISIBLE (-3540 4310);
FORCEPROP 1 LASTPIN (-3550 4300) BN 5
J 0
(-3562 4308);
DISPLAY 0.489362 (-3562 4308);
PAINT GREEN (-3562 4308);
FORCEPROP 2 LAST CDS_LIB mstr_standard
J 0
(-3500 4300);
DISPLAY 0.723404 (-3500 4300);
PAINT MONO (-3500 4300);
DISPLAY INVISIBLE (-3500 4300);
FORCEPROP 1 LAST BODY_TYPE PLUMBING
J 0
(-3500 4350);
DISPLAY 0.872340 (-3500 4350);
PAINT GREEN (-3500 4350);
DISPLAY INVISIBLE (-3500 4350);
FORCEPROP 1 LAST HDL_TAP TRUE
J 0
(-3175 4175);
DISPLAY 0.872340 (-3175 4175);
DISPLAY INVISIBLE (-3175 4175);
FORCEPROP 1 LAST PATH I210
J 0
(-3502 4300);
DISPLAY 0.872340 (-3502 4300);
PAINT GREEN (-3502 4300);
DISPLAY INVISIBLE (-3502 4300);
FORCEADD TAP..1
(-3500 3900);
FORCEPROP 3 LASTPIN (-3550 3900) SIG_NAME M_F_CPU1_SA_DQS_DP<1>
J 0
(-3540 3910);
DISPLAY 0.659574 (-3540 3910);
PAINT MONO (-3540 3910);
DISPLAY INVISIBLE (-3540 3910);
FORCEPROP 1 LASTPIN (-3550 3900) BN 1
J 0
(-3562 3908);
DISPLAY 0.489362 (-3562 3908);
PAINT GREEN (-3562 3908);
FORCEPROP 2 LAST CDS_LIB mstr_standard
J 0
(-3500 3900);
DISPLAY 0.723404 (-3500 3900);
PAINT MONO (-3500 3900);
DISPLAY INVISIBLE (-3500 3900);
FORCEPROP 1 LAST BODY_TYPE PLUMBING
J 0
(-3500 3950);
DISPLAY 0.872340 (-3500 3950);
PAINT GREEN (-3500 3950);
DISPLAY INVISIBLE (-3500 3950);
FORCEPROP 1 LAST HDL_TAP TRUE
J 0
(-3175 3775);
DISPLAY 0.872340 (-3175 3775);
DISPLAY INVISIBLE (-3175 3775);
FORCEPROP 1 LAST PATH I211
J 0
(-3502 3900);
DISPLAY 0.872340 (-3502 3900);
PAINT GREEN (-3502 3900);
DISPLAY INVISIBLE (-3502 3900);
FORCEADD TAP..1
(-3500 4100);
FORCEPROP 3 LASTPIN (-3550 4100) SIG_NAME M_F_CPU1_SA_DQS_DP<3>
J 0
(-3540 4110);
DISPLAY 0.659574 (-3540 4110);
PAINT MONO (-3540 4110);
DISPLAY INVISIBLE (-3540 4110);
FORCEPROP 1 LASTPIN (-3550 4100) BN 3
J 0
(-3562 4108);
DISPLAY 0.489362 (-3562 4108);
PAINT GREEN (-3562 4108);
FORCEPROP 2 LAST CDS_LIB mstr_standard
J 0
(-3500 4100);
DISPLAY 0.723404 (-3500 4100);
PAINT MONO (-3500 4100);
DISPLAY INVISIBLE (-3500 4100);
FORCEPROP 1 LAST BODY_TYPE PLUMBING
J 0
(-3500 4150);
DISPLAY 0.872340 (-3500 4150);
PAINT GREEN (-3500 4150);
DISPLAY INVISIBLE (-3500 4150);
FORCEPROP 1 LAST HDL_TAP TRUE
J 0
(-3175 3975);
DISPLAY 0.872340 (-3175 3975);
DISPLAY INVISIBLE (-3175 3975);
FORCEPROP 1 LAST PATH I212
J 0
(-3502 4100);
DISPLAY 0.872340 (-3502 4100);
PAINT GREEN (-3502 4100);
DISPLAY INVISIBLE (-3502 4100);
FORCEADD TAP..1
(-3300 3750);
FORCEPROP 3 LASTPIN (-3350 3750) SIG_NAME M_F_CPU1_SA_DQS_DN<0>
J 0
(-3340 3760);
DISPLAY 0.659574 (-3340 3760);
PAINT MONO (-3340 3760);
DISPLAY INVISIBLE (-3340 3760);
FORCEPROP 1 LASTPIN (-3350 3750) BN 0
J 0
(-3362 3758);
DISPLAY 0.489362 (-3362 3758);
PAINT GREEN (-3362 3758);
FORCEPROP 2 LAST CDS_LIB mstr_standard
J 0
(-3300 3750);
DISPLAY 0.723404 (-3300 3750);
PAINT MONO (-3300 3750);
DISPLAY INVISIBLE (-3300 3750);
FORCEPROP 1 LAST BODY_TYPE PLUMBING
J 0
(-3300 3800);
DISPLAY 0.872340 (-3300 3800);
PAINT GREEN (-3300 3800);
DISPLAY INVISIBLE (-3300 3800);
FORCEPROP 1 LAST HDL_TAP TRUE
J 0
(-2975 3625);
DISPLAY 0.872340 (-2975 3625);
DISPLAY INVISIBLE (-2975 3625);
FORCEPROP 1 LAST PATH I213
J 0
(-3302 3750);
DISPLAY 0.872340 (-3302 3750);
PAINT GREEN (-3302 3750);
DISPLAY INVISIBLE (-3302 3750);
FORCEADD TAP..1
(-3300 3850);
FORCEPROP 3 LASTPIN (-3350 3850) SIG_NAME M_F_CPU1_SA_DQS_DN<1>
J 0
(-3340 3860);
DISPLAY 0.659574 (-3340 3860);
PAINT MONO (-3340 3860);
DISPLAY INVISIBLE (-3340 3860);
FORCEPROP 1 LASTPIN (-3350 3850) BN 1
J 0
(-3362 3858);
DISPLAY 0.489362 (-3362 3858);
PAINT GREEN (-3362 3858);
FORCEPROP 2 LAST CDS_LIB mstr_standard
J 0
(-3300 3850);
DISPLAY 0.723404 (-3300 3850);
PAINT MONO (-3300 3850);
DISPLAY INVISIBLE (-3300 3850);
FORCEPROP 1 LAST BODY_TYPE PLUMBING
J 0
(-3300 3900);
DISPLAY 0.872340 (-3300 3900);
PAINT GREEN (-3300 3900);
DISPLAY INVISIBLE (-3300 3900);
FORCEPROP 1 LAST HDL_TAP TRUE
J 0
(-2975 3725);
DISPLAY 0.872340 (-2975 3725);
DISPLAY INVISIBLE (-2975 3725);
FORCEPROP 1 LAST PATH I214
J 0
(-3302 3850);
DISPLAY 0.872340 (-3302 3850);
PAINT GREEN (-3302 3850);
DISPLAY INVISIBLE (-3302 3850);
FORCEADD TAP..1
(-3300 3600);
FORCEPROP 3 LASTPIN (-3350 3600) SIG_NAME M_F_CPU1_SB_DQS_DN<9>
J 0
(-3340 3610);
DISPLAY 0.659574 (-3340 3610);
PAINT MONO (-3340 3610);
DISPLAY INVISIBLE (-3340 3610);
FORCEPROP 1 LASTPIN (-3350 3600) BN 9
J 0
(-3362 3608);
DISPLAY 0.489362 (-3362 3608);
PAINT GREEN (-3362 3608);
FORCEPROP 2 LAST CDS_LIB mstr_standard
J 0
(-3300 3600);
DISPLAY 0.723404 (-3300 3600);
PAINT MONO (-3300 3600);
DISPLAY INVISIBLE (-3300 3600);
FORCEPROP 1 LAST BODY_TYPE PLUMBING
J 0
(-3300 3650);
DISPLAY 0.872340 (-3300 3650);
PAINT GREEN (-3300 3650);
DISPLAY INVISIBLE (-3300 3650);
FORCEPROP 1 LAST HDL_TAP TRUE
J 0
(-2975 3475);
DISPLAY 0.872340 (-2975 3475);
DISPLAY INVISIBLE (-2975 3475);
FORCEPROP 1 LAST PATH I215
J 0
(-3302 3600);
DISPLAY 0.872340 (-3302 3600);
PAINT GREEN (-3302 3600);
DISPLAY INVISIBLE (-3302 3600);
FORCEADD TAP..1
(-3300 3500);
FORCEPROP 3 LASTPIN (-3350 3500) SIG_NAME M_F_CPU1_SB_DQS_DN<8>
J 0
(-3340 3510);
DISPLAY 0.659574 (-3340 3510);
PAINT MONO (-3340 3510);
DISPLAY INVISIBLE (-3340 3510);
FORCEPROP 1 LASTPIN (-3350 3500) BN 8
J 0
(-3362 3508);
DISPLAY 0.489362 (-3362 3508);
PAINT GREEN (-3362 3508);
FORCEPROP 2 LAST CDS_LIB mstr_standard
J 0
(-3300 3500);
DISPLAY 0.723404 (-3300 3500);
PAINT MONO (-3300 3500);
DISPLAY INVISIBLE (-3300 3500);
FORCEPROP 1 LAST BODY_TYPE PLUMBING
J 0
(-3300 3550);
DISPLAY 0.872340 (-3300 3550);
PAINT GREEN (-3300 3550);
DISPLAY INVISIBLE (-3300 3550);
FORCEPROP 1 LAST HDL_TAP TRUE
J 0
(-2975 3375);
DISPLAY 0.872340 (-2975 3375);
DISPLAY INVISIBLE (-2975 3375);
FORCEPROP 1 LAST PATH I216
J 0
(-3302 3500);
DISPLAY 0.872340 (-3302 3500);
PAINT GREEN (-3302 3500);
DISPLAY INVISIBLE (-3302 3500);
FORCEADD TAP..1
(-3300 3400);
FORCEPROP 3 LASTPIN (-3350 3400) SIG_NAME M_F_CPU1_SB_DQS_DN<7>
J 0
(-3340 3410);
DISPLAY 0.659574 (-3340 3410);
PAINT MONO (-3340 3410);
DISPLAY INVISIBLE (-3340 3410);
FORCEPROP 1 LASTPIN (-3350 3400) BN 7
J 0
(-3362 3408);
DISPLAY 0.489362 (-3362 3408);
PAINT GREEN (-3362 3408);
FORCEPROP 2 LAST CDS_LIB mstr_standard
J 0
(-3300 3400);
DISPLAY 0.723404 (-3300 3400);
PAINT MONO (-3300 3400);
DISPLAY INVISIBLE (-3300 3400);
FORCEPROP 1 LAST BODY_TYPE PLUMBING
J 0
(-3300 3450);
DISPLAY 0.872340 (-3300 3450);
PAINT GREEN (-3300 3450);
DISPLAY INVISIBLE (-3300 3450);
FORCEPROP 1 LAST HDL_TAP TRUE
J 0
(-2975 3275);
DISPLAY 0.872340 (-2975 3275);
DISPLAY INVISIBLE (-2975 3275);
FORCEPROP 1 LAST PATH I217
J 0
(-3302 3400);
DISPLAY 0.872340 (-3302 3400);
PAINT GREEN (-3302 3400);
DISPLAY INVISIBLE (-3302 3400);
FORCEADD TAP..1
(-3500 3650);
FORCEPROP 3 LASTPIN (-3550 3650) SIG_NAME M_F_CPU1_SB_DQS_DP<9>
J 0
(-3540 3660);
DISPLAY 0.659574 (-3540 3660);
PAINT MONO (-3540 3660);
DISPLAY INVISIBLE (-3540 3660);
FORCEPROP 1 LASTPIN (-3550 3650) BN 9
J 0
(-3562 3658);
DISPLAY 0.489362 (-3562 3658);
PAINT GREEN (-3562 3658);
FORCEPROP 2 LAST CDS_LIB mstr_standard
J 0
(-3500 3650);
DISPLAY 0.723404 (-3500 3650);
PAINT MONO (-3500 3650);
DISPLAY INVISIBLE (-3500 3650);
FORCEPROP 1 LAST BODY_TYPE PLUMBING
J 0
(-3500 3700);
DISPLAY 0.872340 (-3500 3700);
PAINT GREEN (-3500 3700);
DISPLAY INVISIBLE (-3500 3700);
FORCEPROP 1 LAST HDL_TAP TRUE
J 0
(-3175 3525);
DISPLAY 0.872340 (-3175 3525);
DISPLAY INVISIBLE (-3175 3525);
FORCEPROP 1 LAST PATH I218
J 0
(-3502 3650);
DISPLAY 0.872340 (-3502 3650);
PAINT GREEN (-3502 3650);
DISPLAY INVISIBLE (-3502 3650);
FORCEADD TAP..1
(-3500 3800);
FORCEPROP 3 LASTPIN (-3550 3800) SIG_NAME M_F_CPU1_SA_DQS_DP<0>
J 0
(-3540 3810);
DISPLAY 0.659574 (-3540 3810);
PAINT MONO (-3540 3810);
DISPLAY INVISIBLE (-3540 3810);
FORCEPROP 1 LASTPIN (-3550 3800) BN 0
J 0
(-3562 3808);
DISPLAY 0.489362 (-3562 3808);
PAINT GREEN (-3562 3808);
FORCEPROP 2 LAST CDS_LIB mstr_standard
J 0
(-3500 3800);
DISPLAY 0.723404 (-3500 3800);
PAINT MONO (-3500 3800);
DISPLAY INVISIBLE (-3500 3800);
FORCEPROP 1 LAST BODY_TYPE PLUMBING
J 0
(-3500 3850);
DISPLAY 0.872340 (-3500 3850);
PAINT GREEN (-3500 3850);
DISPLAY INVISIBLE (-3500 3850);
FORCEPROP 1 LAST HDL_TAP TRUE
J 0
(-3175 3675);
DISPLAY 0.872340 (-3175 3675);
DISPLAY INVISIBLE (-3175 3675);
FORCEPROP 1 LAST PATH I219
J 0
(-3502 3800);
DISPLAY 0.872340 (-3502 3800);
PAINT GREEN (-3502 3800);
DISPLAY INVISIBLE (-3502 3800);
FORCEADD SCONN288_DDR506112002KQ..1
(-6975 3775);
FORCEPROP 1 LAST LOCATION J33
J 0
(-7425 5850);
DISPLAY 0.468085 (-7425 5850);
PAINT SKYBLUE (-7425 5850);
FORCEPROP 0 LAST $SEC 1
J 0
(-7425 6000);
DISPLAY 0.680851 (-7425 6000);
PAINT MONO (-7425 6000);
DISPLAY INVISIBLE (-7425 6000);
FORCEPROP 2 LAST CDS_SEC 1
J 0
(-7425 6000);
DISPLAY 1.021277 (-7425 6000);
DISPLAY INVISIBLE (-7425 6000);
FORCEPROP 0 LASTPIN (-7575 3175) $PN 62
J 2
(-7585 3185);
DISPLAY 0.680851 (-7585 3185);
PAINT MONO (-7585 3185);
FORCEPROP 0 LASTPIN (-7575 5225) $PN 66
J 2
(-7585 5235);
DISPLAY 0.680851 (-7585 5235);
PAINT MONO (-7585 5235);
FORCEPROP 0 LASTPIN (-7575 4825) $PN 76
J 2
(-7585 4835);
DISPLAY 0.680851 (-7585 4835);
PAINT MONO (-7585 4835);
FORCEPROP 0 LASTPIN (-7575 5275) $PN 211
J 2
(-7585 5285);
DISPLAY 0.680851 (-7585 5285);
PAINT MONO (-7585 5285);
FORCEPROP 0 LASTPIN (-7575 4875) $PN 221
J 2
(-7585 4885);
DISPLAY 0.680851 (-7585 4885);
PAINT MONO (-7585 4885);
FORCEPROP 0 LASTPIN (-7575 5325) $PN 68
J 2
(-7585 5335);
DISPLAY 0.680851 (-7585 5335);
PAINT MONO (-7585 5335);
FORCEPROP 0 LASTPIN (-7575 4925) $PN 78
J 2
(-7585 4935);
DISPLAY 0.680851 (-7585 4935);
PAINT MONO (-7585 4935);
FORCEPROP 0 LASTPIN (-7575 5375) $PN 213
J 2
(-7585 5385);
DISPLAY 0.680851 (-7585 5385);
PAINT MONO (-7585 5385);
FORCEPROP 0 LASTPIN (-7575 4975) $PN 223
J 2
(-7585 4985);
DISPLAY 0.680851 (-7585 4985);
PAINT MONO (-7585 4985);
FORCEPROP 0 LASTPIN (-7575 5425) $PN 70
J 2
(-7585 5435);
DISPLAY 0.680851 (-7585 5435);
PAINT MONO (-7585 5435);
FORCEPROP 0 LASTPIN (-7575 5025) $PN 80
J 2
(-7585 5035);
DISPLAY 0.680851 (-7585 5035);
PAINT MONO (-7585 5035);
FORCEPROP 0 LASTPIN (-7575 5475) $PN 215
J 2
(-7585 5485);
DISPLAY 0.680851 (-7585 5485);
PAINT MONO (-7585 5485);
FORCEPROP 0 LASTPIN (-7575 5075) $PN 225
J 2
(-7585 5085);
DISPLAY 0.680851 (-7585 5085);
PAINT MONO (-7585 5085);
FORCEPROP 0 LASTPIN (-7575 5525) $PN 72
J 2
(-7585 5535);
DISPLAY 0.680851 (-7585 5535);
PAINT MONO (-7585 5535);
FORCEPROP 0 LASTPIN (-7575 5125) $PN 82
J 2
(-7585 5135);
DISPLAY 0.680851 (-7585 5135);
PAINT MONO (-7585 5135);
FORCEPROP 0 LASTPIN (-7575 3775) $PN 51
J 2
(-7585 3785);
DISPLAY 0.680851 (-7585 3785);
PAINT MONO (-7585 3785);
FORCEPROP 0 LASTPIN (-7575 3325) $PN 96
J 2
(-7585 3335);
DISPLAY 0.680851 (-7585 3335);
PAINT MONO (-7585 3335);
FORCEPROP 0 LASTPIN (-7575 3825) $PN 53
J 2
(-7585 3835);
DISPLAY 0.680851 (-7585 3835);
PAINT MONO (-7585 3835);
FORCEPROP 0 LASTPIN (-7575 3375) $PN 98
J 2
(-7585 3385);
DISPLAY 0.680851 (-7585 3385);
PAINT MONO (-7585 3385);
FORCEPROP 0 LASTPIN (-7575 3875) $PN 196
J 2
(-7585 3885);
DISPLAY 0.680851 (-7585 3885);
PAINT MONO (-7585 3885);
FORCEPROP 0 LASTPIN (-7575 3425) $PN 241
J 2
(-7585 3435);
DISPLAY 0.680851 (-7585 3435);
PAINT MONO (-7585 3435);
FORCEPROP 0 LASTPIN (-7575 3925) $PN 198
J 2
(-7585 3935);
DISPLAY 0.680851 (-7585 3935);
PAINT MONO (-7585 3935);
FORCEPROP 0 LASTPIN (-7575 3475) $PN 243
J 2
(-7585 3485);
DISPLAY 0.680851 (-7585 3485);
PAINT MONO (-7585 3485);
FORCEPROP 0 LASTPIN (-7575 3975) $PN 58
J 2
(-7585 3985);
DISPLAY 0.680851 (-7585 3985);
PAINT MONO (-7585 3985);
FORCEPROP 0 LASTPIN (-7575 3525) $PN 89
J 2
(-7585 3535);
DISPLAY 0.680851 (-7585 3535);
PAINT MONO (-7585 3535);
FORCEPROP 0 LASTPIN (-7575 4025) $PN 60
J 2
(-7585 4035);
DISPLAY 0.680851 (-7585 4035);
PAINT MONO (-7585 4035);
FORCEPROP 0 LASTPIN (-7575 3575) $PN 91
J 2
(-7585 3585);
DISPLAY 0.680851 (-7585 3585);
PAINT MONO (-7585 3585);
FORCEPROP 0 LASTPIN (-7575 4075) $PN 203
J 2
(-7585 4085);
DISPLAY 0.680851 (-7585 4085);
PAINT MONO (-7585 4085);
FORCEPROP 0 LASTPIN (-7575 3625) $PN 234
J 2
(-7585 3635);
DISPLAY 0.680851 (-7585 3635);
PAINT MONO (-7585 3635);
FORCEPROP 0 LASTPIN (-7575 4125) $PN 205
J 2
(-7585 4135);
DISPLAY 0.680851 (-7585 4135);
PAINT MONO (-7585 4135);
FORCEPROP 0 LASTPIN (-7575 3675) $PN 236
J 2
(-7585 3685);
DISPLAY 0.680851 (-7585 3685);
PAINT MONO (-7585 3685);
FORCEPROP 0 LASTPIN (-7575 4225) $PN 218
J 2
(-7585 4235);
DISPLAY 0.680851 (-7585 4235);
PAINT MONO (-7585 4235);
FORCEPROP 0 LASTPIN (-7575 4275) $PN 217
J 2
(-7585 4285);
DISPLAY 0.680851 (-7585 4285);
PAINT MONO (-7585 4285);
FORCEPROP 0 LASTPIN (-7575 4525) $PN 64
J 2
(-7585 4535);
DISPLAY 0.680851 (-7585 4535);
PAINT MONO (-7585 4535);
FORCEPROP 0 LASTPIN (-7575 4375) $PN 84
J 2
(-7585 4385);
DISPLAY 0.680851 (-7585 4385);
PAINT MONO (-7585 4385);
FORCEPROP 0 LASTPIN (-7575 4575) $PN 209
J 2
(-7585 4585);
DISPLAY 0.680851 (-7585 4585);
PAINT MONO (-7585 4585);
FORCEPROP 0 LASTPIN (-7575 4425) $PN 229
J 2
(-7585 4435);
DISPLAY 0.680851 (-7585 4435);
PAINT MONO (-7585 4435);
FORCEPROP 0 LASTPIN (-6375 3975) $PN 7
J 0
(-6365 3985);
DISPLAY 0.680851 (-6365 3985);
PAINT MONO (-6365 3985);
FORCEPROP 0 LASTPIN (-6375 2325) $PN 100
J 0
(-6365 2335);
DISPLAY 0.680851 (-6365 2335);
PAINT MONO (-6365 2335);
FORCEPROP 0 LASTPIN (-6375 4025) $PN 9
J 0
(-6365 4035);
DISPLAY 0.680851 (-6365 4035);
PAINT MONO (-6365 4035);
FORCEPROP 0 LASTPIN (-6375 2375) $PN 102
J 0
(-6365 2385);
DISPLAY 0.680851 (-6365 2385);
PAINT MONO (-6365 2385);
FORCEPROP 0 LASTPIN (-6375 4075) $PN 152
J 0
(-6365 4085);
DISPLAY 0.680851 (-6365 4085);
PAINT MONO (-6365 4085);
FORCEPROP 0 LASTPIN (-6375 2425) $PN 245
J 0
(-6365 2435);
DISPLAY 0.680851 (-6365 2435);
PAINT MONO (-6365 2435);
FORCEPROP 0 LASTPIN (-6375 4125) $PN 154
J 0
(-6365 4135);
DISPLAY 0.680851 (-6365 4135);
PAINT MONO (-6365 4135);
FORCEPROP 0 LASTPIN (-6375 2475) $PN 247
J 0
(-6365 2485);
DISPLAY 0.680851 (-6365 2485);
PAINT MONO (-6365 2485);
FORCEPROP 0 LASTPIN (-6375 4175) $PN 14
J 0
(-6365 4185);
DISPLAY 0.680851 (-6365 4185);
PAINT MONO (-6365 4185);
FORCEPROP 0 LASTPIN (-6375 2525) $PN 107
J 0
(-6365 2535);
DISPLAY 0.680851 (-6365 2535);
PAINT MONO (-6365 2535);
FORCEPROP 0 LASTPIN (-6375 4225) $PN 16
J 0
(-6365 4235);
DISPLAY 0.680851 (-6365 4235);
PAINT MONO (-6365 4235);
FORCEPROP 0 LASTPIN (-6375 2575) $PN 109
J 0
(-6365 2585);
DISPLAY 0.680851 (-6365 2585);
PAINT MONO (-6365 2585);
FORCEPROP 0 LASTPIN (-6375 4275) $PN 159
J 0
(-6365 4285);
DISPLAY 0.680851 (-6365 4285);
PAINT MONO (-6365 4285);
FORCEPROP 0 LASTPIN (-6375 2625) $PN 252
J 0
(-6365 2635);
DISPLAY 0.680851 (-6365 2635);
PAINT MONO (-6365 2635);
FORCEPROP 0 LASTPIN (-6375 4325) $PN 161
J 0
(-6365 4335);
DISPLAY 0.680851 (-6365 4335);
PAINT MONO (-6365 4335);
FORCEPROP 0 LASTPIN (-6375 2675) $PN 254
J 0
(-6365 2685);
DISPLAY 0.680851 (-6365 2685);
PAINT MONO (-6365 2685);
FORCEPROP 0 LASTPIN (-6375 4375) $PN 18
J 0
(-6365 4385);
DISPLAY 0.680851 (-6365 4385);
PAINT MONO (-6365 4385);
FORCEPROP 0 LASTPIN (-6375 2725) $PN 111
J 0
(-6365 2735);
DISPLAY 0.680851 (-6365 2735);
PAINT MONO (-6365 2735);
FORCEPROP 0 LASTPIN (-6375 4425) $PN 20
J 0
(-6365 4435);
DISPLAY 0.680851 (-6365 4435);
PAINT MONO (-6365 4435);
FORCEPROP 0 LASTPIN (-6375 2775) $PN 113
J 0
(-6365 2785);
DISPLAY 0.680851 (-6365 2785);
PAINT MONO (-6365 2785);
FORCEPROP 0 LASTPIN (-6375 4475) $PN 163
J 0
(-6365 4485);
DISPLAY 0.680851 (-6365 4485);
PAINT MONO (-6365 4485);
FORCEPROP 0 LASTPIN (-6375 2825) $PN 256
J 0
(-6365 2835);
DISPLAY 0.680851 (-6365 2835);
PAINT MONO (-6365 2835);
FORCEPROP 0 LASTPIN (-6375 4525) $PN 165
J 0
(-6365 4535);
DISPLAY 0.680851 (-6365 4535);
PAINT MONO (-6365 4535);
FORCEPROP 0 LASTPIN (-6375 2875) $PN 258
J 0
(-6365 2885);
DISPLAY 0.680851 (-6365 2885);
PAINT MONO (-6365 2885);
FORCEPROP 0 LASTPIN (-6375 4575) $PN 25
J 0
(-6365 4585);
DISPLAY 0.680851 (-6365 4585);
PAINT MONO (-6365 4585);
FORCEPROP 0 LASTPIN (-6375 2925) $PN 118
J 0
(-6365 2935);
DISPLAY 0.680851 (-6365 2935);
PAINT MONO (-6365 2935);
FORCEPROP 0 LASTPIN (-6375 4625) $PN 27
J 0
(-6365 4635);
DISPLAY 0.680851 (-6365 4635);
PAINT MONO (-6365 4635);
FORCEPROP 0 LASTPIN (-6375 2975) $PN 120
J 0
(-6365 2985);
DISPLAY 0.680851 (-6365 2985);
PAINT MONO (-6365 2985);
FORCEPROP 0 LASTPIN (-6375 4675) $PN 170
J 0
(-6365 4685);
DISPLAY 0.680851 (-6365 4685);
PAINT MONO (-6365 4685);
FORCEPROP 0 LASTPIN (-6375 3025) $PN 263
J 0
(-6365 3035);
DISPLAY 0.680851 (-6365 3035);
PAINT MONO (-6365 3035);
FORCEPROP 0 LASTPIN (-6375 4725) $PN 172
J 0
(-6365 4735);
DISPLAY 0.680851 (-6365 4735);
PAINT MONO (-6365 4735);
FORCEPROP 0 LASTPIN (-6375 3075) $PN 265
J 0
(-6365 3085);
DISPLAY 0.680851 (-6365 3085);
PAINT MONO (-6365 3085);
FORCEPROP 0 LASTPIN (-6375 4775) $PN 29
J 0
(-6365 4785);
DISPLAY 0.680851 (-6365 4785);
PAINT MONO (-6365 4785);
FORCEPROP 0 LASTPIN (-6375 3125) $PN 122
J 0
(-6365 3135);
DISPLAY 0.680851 (-6365 3135);
PAINT MONO (-6365 3135);
FORCEPROP 0 LASTPIN (-6375 4825) $PN 31
J 0
(-6365 4835);
DISPLAY 0.680851 (-6365 4835);
PAINT MONO (-6365 4835);
FORCEPROP 0 LASTPIN (-6375 3175) $PN 124
J 0
(-6365 3185);
DISPLAY 0.680851 (-6365 3185);
PAINT MONO (-6365 3185);
FORCEPROP 0 LASTPIN (-6375 4875) $PN 174
J 0
(-6365 4885);
DISPLAY 0.680851 (-6365 4885);
PAINT MONO (-6365 4885);
FORCEPROP 0 LASTPIN (-6375 3225) $PN 267
J 0
(-6365 3235);
DISPLAY 0.680851 (-6365 3235);
PAINT MONO (-6365 3235);
FORCEPROP 0 LASTPIN (-6375 4925) $PN 176
J 0
(-6365 4935);
DISPLAY 0.680851 (-6365 4935);
PAINT MONO (-6365 4935);
FORCEPROP 0 LASTPIN (-6375 3275) $PN 269
J 0
(-6365 3285);
DISPLAY 0.680851 (-6365 3285);
PAINT MONO (-6365 3285);
FORCEPROP 0 LASTPIN (-6375 4975) $PN 36
J 0
(-6365 4985);
DISPLAY 0.680851 (-6365 4985);
PAINT MONO (-6365 4985);
FORCEPROP 0 LASTPIN (-6375 3325) $PN 129
J 0
(-6365 3335);
DISPLAY 0.680851 (-6365 3335);
PAINT MONO (-6365 3335);
FORCEPROP 0 LASTPIN (-6375 5025) $PN 38
J 0
(-6365 5035);
DISPLAY 0.680851 (-6365 5035);
PAINT MONO (-6365 5035);
FORCEPROP 0 LASTPIN (-6375 3375) $PN 131
J 0
(-6365 3385);
DISPLAY 0.680851 (-6365 3385);
PAINT MONO (-6365 3385);
FORCEPROP 0 LASTPIN (-6375 5075) $PN 181
J 0
(-6365 5085);
DISPLAY 0.680851 (-6365 5085);
PAINT MONO (-6365 5085);
FORCEPROP 0 LASTPIN (-6375 3425) $PN 274
J 0
(-6365 3435);
DISPLAY 0.680851 (-6365 3435);
PAINT MONO (-6365 3435);
FORCEPROP 0 LASTPIN (-6375 5125) $PN 183
J 0
(-6365 5135);
DISPLAY 0.680851 (-6365 5135);
PAINT MONO (-6365 5135);
FORCEPROP 0 LASTPIN (-6375 3475) $PN 276
J 0
(-6365 3485);
DISPLAY 0.680851 (-6365 3485);
PAINT MONO (-6365 3485);
FORCEPROP 0 LASTPIN (-6375 5175) $PN 40
J 0
(-6365 5185);
DISPLAY 0.680851 (-6365 5185);
PAINT MONO (-6365 5185);
FORCEPROP 0 LASTPIN (-6375 3525) $PN 133
J 0
(-6365 3535);
DISPLAY 0.680851 (-6365 3535);
PAINT MONO (-6365 3535);
FORCEPROP 0 LASTPIN (-6375 5225) $PN 42
J 0
(-6365 5235);
DISPLAY 0.680851 (-6365 5235);
PAINT MONO (-6365 5235);
FORCEPROP 0 LASTPIN (-6375 3575) $PN 135
J 0
(-6365 3585);
DISPLAY 0.680851 (-6365 3585);
PAINT MONO (-6365 3585);
FORCEPROP 0 LASTPIN (-6375 5275) $PN 185
J 0
(-6365 5285);
DISPLAY 0.680851 (-6365 5285);
PAINT MONO (-6365 5285);
FORCEPROP 0 LASTPIN (-6375 3625) $PN 278
J 0
(-6365 3635);
DISPLAY 0.680851 (-6365 3635);
PAINT MONO (-6365 3635);
FORCEPROP 0 LASTPIN (-6375 5325) $PN 187
J 0
(-6365 5335);
DISPLAY 0.680851 (-6365 5335);
PAINT MONO (-6365 5335);
FORCEPROP 0 LASTPIN (-6375 3675) $PN 280
J 0
(-6365 3685);
DISPLAY 0.680851 (-6365 3685);
PAINT MONO (-6365 3685);
FORCEPROP 0 LASTPIN (-6375 5375) $PN 47
J 0
(-6365 5385);
DISPLAY 0.680851 (-6365 5385);
PAINT MONO (-6365 5385);
FORCEPROP 0 LASTPIN (-6375 3725) $PN 140
J 0
(-6365 3735);
DISPLAY 0.680851 (-6365 3735);
PAINT MONO (-6365 3735);
FORCEPROP 0 LASTPIN (-6375 5425) $PN 49
J 0
(-6365 5435);
DISPLAY 0.680851 (-6365 5435);
PAINT MONO (-6365 5435);
FORCEPROP 0 LASTPIN (-6375 3775) $PN 142
J 0
(-6365 3785);
DISPLAY 0.680851 (-6365 3785);
PAINT MONO (-6365 3785);
FORCEPROP 0 LASTPIN (-6375 5475) $PN 192
J 0
(-6365 5485);
DISPLAY 0.680851 (-6365 5485);
PAINT MONO (-6365 5485);
FORCEPROP 0 LASTPIN (-6375 3825) $PN 285
J 0
(-6365 3835);
DISPLAY 0.680851 (-6365 3835);
PAINT MONO (-6365 3835);
FORCEPROP 0 LASTPIN (-6375 5525) $PN 194
J 0
(-6365 5535);
DISPLAY 0.680851 (-6365 5535);
PAINT MONO (-6365 5535);
FORCEPROP 0 LASTPIN (-6375 3875) $PN 287
J 0
(-6365 3885);
DISPLAY 0.680851 (-6365 3885);
PAINT MONO (-6365 3885);
FORCEPROP 0 LASTPIN (-7575 3025) $PN 148
J 2
(-7585 3035);
DISPLAY 0.680851 (-7585 3035);
PAINT MONO (-7585 3035);
FORCEPROP 0 LASTPIN (-7575 2925) $PN 4
J 2
(-7585 2935);
DISPLAY 0.680851 (-7585 2935);
PAINT MONO (-7585 2935);
FORCEPROP 0 LASTPIN (-7575 2975) $PN 5
J 2
(-7585 2985);
DISPLAY 0.680851 (-7585 2985);
PAINT MONO (-7585 2985);
FORCEPROP 0 LASTPIN (-7575 2125) $PN 86
J 2
(-7585 2135);
DISPLAY 0.680851 (-7585 2135);
PAINT MONO (-7585 2135);
FORCEPROP 0 LASTPIN (-7575 2075) $PN 87
J 2
(-7585 2085);
DISPLAY 0.680851 (-7585 2085);
PAINT MONO (-7585 2085);
FORCEPROP 0 LASTPIN (-7575 4725) $PN 74
J 2
(-7585 4735);
DISPLAY 0.680851 (-7585 4735);
PAINT MONO (-7585 4735);
FORCEPROP 0 LASTPIN (-7575 4675) $PN 227
J 2
(-7585 4685);
DISPLAY 0.680851 (-7585 4685);
PAINT MONO (-7585 4685);
FORCEPROP 0 LASTPIN (-7575 2675) $PN 147
J 2
(-7585 2685);
DISPLAY 0.680851 (-7585 2685);
PAINT MONO (-7585 2685);
FORCEPROP 0 LASTPIN (-7575 3225) $PN 207
J 2
(-7585 3235);
DISPLAY 0.680851 (-7585 3235);
PAINT MONO (-7585 3235);
FORCEPROP 0 LASTPIN (-7575 2275) $PN 2
J 2
(-7585 2285);
DISPLAY 0.680851 (-7585 2285);
PAINT MONO (-7585 2285);
FORCEPROP 0 LASTPIN (-7575 2325) $PN 144
J 2
(-7585 2335);
DISPLAY 0.680851 (-7585 2335);
PAINT MONO (-7585 2335);
FORCEPROP 0 LASTPIN (-7575 2375) $PN 149
J 2
(-7585 2385);
DISPLAY 0.680851 (-7585 2385);
PAINT MONO (-7585 2385);
FORCEPROP 0 LASTPIN (-7575 2425) $PN 150
J 2
(-7585 2435);
DISPLAY 0.680851 (-7585 2435);
PAINT MONO (-7585 2435);
FORCEPROP 0 LASTPIN (-7575 2475) $PN 220
J 2
(-7585 2485);
DISPLAY 0.680851 (-7585 2485);
PAINT MONO (-7585 2485);
FORCEPROP 0 LASTPIN (-7575 2525) $PN 231
J 2
(-7585 2535);
DISPLAY 0.680851 (-7585 2535);
PAINT MONO (-7585 2535);
FORCEPROP 0 LASTPIN (-7575 2575) $PN 232
J 2
(-7585 2585);
DISPLAY 0.680851 (-7585 2585);
PAINT MONO (-7585 2585);
FORCEPROP 0 LASTPIN (-7575 3075) $PN 3
J 2
(-7585 3085);
DISPLAY 0.680851 (-7585 3085);
PAINT MONO (-7585 3085);
FORCEPROP 2 LAST PART_TYPE SMLF
J 0
(-7425 5950);
DISPLAY 1.021277 (-7425 5950);
FORCEPROP 2 LAST VALUE SCONN288_DDR506112002KQ
J 0
(-7425 5900);
DISPLAY 0.489362 (-7425 5900);
PAINT SKYBLUE (-7425 5900);
FORCEPROP 1 LAST MATERIAL IO
J 0
(-7425 5700);
DISPLAY 0.468085 (-7425 5700);
PAINT SKYBLUE (-7425 5700);
FORCEPROP 1 LAST CDS_LMAN_SYM_OUTLINE -450,1900,450,-1850
J 0
(-6975 3775);
DISPLAY 0.468085 (-6975 3775);
PAINT GREEN (-6975 3775);
DISPLAY INVISIBLE (-6975 3775);
FORCEPROP 1 LAST NEEDS_NO_SIZE TRUE
J 0
(-6975 3775);
DISPLAY 0.723404 (-6975 3775);
PAINT GREEN (-6975 3775);
DISPLAY INVISIBLE (-6975 3775);
FORCEPROP 2 LAST CDS_LIB pure_quanta
J 0
(-6975 3775);
DISPLAY INVISIBLE (-6975 3775);
FORCEPROP 1 LAST PATH I22
J 0
(-6975 3775);
DISPLAY 0.723404 (-6975 3775);
PAINT GREEN (-6975 3775);
DISPLAY INVISIBLE (-6975 3775);
FORCEPROP 1 LAST PART_NUMBER DFHST8FS479
J 0
(-7425 5775);
DISPLAY 0.468085 (-7425 5775);
PAINT SKYBLUE (-7425 5775);
DISPLAY INVISIBLE (-7425 5775);
FORCEADD TAP..1
(-3500 3550);
FORCEPROP 3 LASTPIN (-3550 3550) SIG_NAME M_F_CPU1_SB_DQS_DP<8>
J 0
(-3540 3560);
DISPLAY 0.659574 (-3540 3560);
PAINT MONO (-3540 3560);
DISPLAY INVISIBLE (-3540 3560);
FORCEPROP 1 LASTPIN (-3550 3550) BN 8
J 0
(-3562 3558);
DISPLAY 0.489362 (-3562 3558);
PAINT GREEN (-3562 3558);
FORCEPROP 2 LAST CDS_LIB mstr_standard
J 0
(-3500 3550);
DISPLAY 0.723404 (-3500 3550);
PAINT MONO (-3500 3550);
DISPLAY INVISIBLE (-3500 3550);
FORCEPROP 1 LAST BODY_TYPE PLUMBING
J 0
(-3500 3600);
DISPLAY 0.872340 (-3500 3600);
PAINT GREEN (-3500 3600);
DISPLAY INVISIBLE (-3500 3600);
FORCEPROP 1 LAST HDL_TAP TRUE
J 0
(-3175 3425);
DISPLAY 0.872340 (-3175 3425);
DISPLAY INVISIBLE (-3175 3425);
FORCEPROP 1 LAST PATH I220
J 0
(-3502 3550);
DISPLAY 0.872340 (-3502 3550);
PAINT GREEN (-3502 3550);
DISPLAY INVISIBLE (-3502 3550);
FORCEADD TAP..1
(-3500 3450);
FORCEPROP 3 LASTPIN (-3550 3450) SIG_NAME M_F_CPU1_SB_DQS_DP<7>
J 0
(-3540 3460);
DISPLAY 0.659574 (-3540 3460);
PAINT MONO (-3540 3460);
DISPLAY INVISIBLE (-3540 3460);
FORCEPROP 1 LASTPIN (-3550 3450) BN 7
J 0
(-3562 3458);
DISPLAY 0.489362 (-3562 3458);
PAINT GREEN (-3562 3458);
FORCEPROP 2 LAST CDS_LIB mstr_standard
J 0
(-3500 3450);
DISPLAY 0.723404 (-3500 3450);
PAINT MONO (-3500 3450);
DISPLAY INVISIBLE (-3500 3450);
FORCEPROP 1 LAST BODY_TYPE PLUMBING
J 0
(-3500 3500);
DISPLAY 0.872340 (-3500 3500);
PAINT GREEN (-3500 3500);
DISPLAY INVISIBLE (-3500 3500);
FORCEPROP 1 LAST HDL_TAP TRUE
J 0
(-3175 3325);
DISPLAY 0.872340 (-3175 3325);
DISPLAY INVISIBLE (-3175 3325);
FORCEPROP 1 LAST PATH I221
J 0
(-3502 3450);
DISPLAY 0.872340 (-3502 3450);
PAINT GREEN (-3502 3450);
DISPLAY INVISIBLE (-3502 3450);
FORCEADD TAP..1
(-3300 3300);
FORCEPROP 3 LASTPIN (-3350 3300) SIG_NAME M_F_CPU1_SB_DQS_DN<6>
J 0
(-3340 3310);
DISPLAY 0.659574 (-3340 3310);
PAINT MONO (-3340 3310);
DISPLAY INVISIBLE (-3340 3310);
FORCEPROP 1 LASTPIN (-3350 3300) BN 6
J 0
(-3362 3308);
DISPLAY 0.489362 (-3362 3308);
PAINT GREEN (-3362 3308);
FORCEPROP 2 LAST CDS_LIB mstr_standard
J 0
(-3300 3300);
DISPLAY 0.723404 (-3300 3300);
PAINT MONO (-3300 3300);
DISPLAY INVISIBLE (-3300 3300);
FORCEPROP 1 LAST BODY_TYPE PLUMBING
J 0
(-3300 3350);
DISPLAY 0.872340 (-3300 3350);
PAINT GREEN (-3300 3350);
DISPLAY INVISIBLE (-3300 3350);
FORCEPROP 1 LAST HDL_TAP TRUE
J 0
(-2975 3175);
DISPLAY 0.872340 (-2975 3175);
DISPLAY INVISIBLE (-2975 3175);
FORCEPROP 1 LAST PATH I222
J 0
(-3302 3300);
DISPLAY 0.872340 (-3302 3300);
PAINT GREEN (-3302 3300);
DISPLAY INVISIBLE (-3302 3300);
FORCEADD TAP..1
(-3300 3200);
FORCEPROP 3 LASTPIN (-3350 3200) SIG_NAME M_F_CPU1_SB_DQS_DN<5>
J 0
(-3340 3210);
DISPLAY 0.659574 (-3340 3210);
PAINT MONO (-3340 3210);
DISPLAY INVISIBLE (-3340 3210);
FORCEPROP 1 LASTPIN (-3350 3200) BN 5
J 0
(-3362 3208);
DISPLAY 0.489362 (-3362 3208);
PAINT GREEN (-3362 3208);
FORCEPROP 2 LAST CDS_LIB mstr_standard
J 0
(-3300 3200);
DISPLAY 0.723404 (-3300 3200);
PAINT MONO (-3300 3200);
DISPLAY INVISIBLE (-3300 3200);
FORCEPROP 1 LAST BODY_TYPE PLUMBING
J 0
(-3300 3250);
DISPLAY 0.872340 (-3300 3250);
PAINT GREEN (-3300 3250);
DISPLAY INVISIBLE (-3300 3250);
FORCEPROP 1 LAST HDL_TAP TRUE
J 0
(-2975 3075);
DISPLAY 0.872340 (-2975 3075);
DISPLAY INVISIBLE (-2975 3075);
FORCEPROP 1 LAST PATH I223
J 0
(-3302 3200);
DISPLAY 0.872340 (-3302 3200);
PAINT GREEN (-3302 3200);
DISPLAY INVISIBLE (-3302 3200);
FORCEADD TAP..1
(-3300 3000);
FORCEPROP 3 LASTPIN (-3350 3000) SIG_NAME M_F_CPU1_SB_DQS_DN<3>
J 0
(-3340 3010);
DISPLAY 0.659574 (-3340 3010);
PAINT MONO (-3340 3010);
DISPLAY INVISIBLE (-3340 3010);
FORCEPROP 1 LASTPIN (-3350 3000) BN 3
J 0
(-3362 3008);
DISPLAY 0.489362 (-3362 3008);
PAINT GREEN (-3362 3008);
FORCEPROP 2 LAST CDS_LIB mstr_standard
J 0
(-3300 3000);
DISPLAY 0.723404 (-3300 3000);
PAINT MONO (-3300 3000);
DISPLAY INVISIBLE (-3300 3000);
FORCEPROP 1 LAST BODY_TYPE PLUMBING
J 0
(-3300 3050);
DISPLAY 0.872340 (-3300 3050);
PAINT GREEN (-3300 3050);
DISPLAY INVISIBLE (-3300 3050);
FORCEPROP 1 LAST HDL_TAP TRUE
J 0
(-2975 2875);
DISPLAY 0.872340 (-2975 2875);
DISPLAY INVISIBLE (-2975 2875);
FORCEPROP 1 LAST PATH I224
J 0
(-3302 3000);
DISPLAY 0.872340 (-3302 3000);
PAINT GREEN (-3302 3000);
DISPLAY INVISIBLE (-3302 3000);
FORCEADD TAP..1
(-3300 3100);
FORCEPROP 3 LASTPIN (-3350 3100) SIG_NAME M_F_CPU1_SB_DQS_DN<4>
J 0
(-3340 3110);
DISPLAY 0.659574 (-3340 3110);
PAINT MONO (-3340 3110);
DISPLAY INVISIBLE (-3340 3110);
FORCEPROP 1 LASTPIN (-3350 3100) BN 4
J 0
(-3362 3108);
DISPLAY 0.489362 (-3362 3108);
PAINT GREEN (-3362 3108);
FORCEPROP 2 LAST CDS_LIB mstr_standard
J 0
(-3300 3100);
DISPLAY 0.723404 (-3300 3100);
PAINT MONO (-3300 3100);
DISPLAY INVISIBLE (-3300 3100);
FORCEPROP 1 LAST BODY_TYPE PLUMBING
J 0
(-3300 3150);
DISPLAY 0.872340 (-3300 3150);
PAINT GREEN (-3300 3150);
DISPLAY INVISIBLE (-3300 3150);
FORCEPROP 1 LAST HDL_TAP TRUE
J 0
(-2975 2975);
DISPLAY 0.872340 (-2975 2975);
DISPLAY INVISIBLE (-2975 2975);
FORCEPROP 1 LAST PATH I225
J 0
(-3302 3100);
DISPLAY 0.872340 (-3302 3100);
PAINT GREEN (-3302 3100);
DISPLAY INVISIBLE (-3302 3100);
FORCEADD TAP..1
(-3300 2900);
FORCEPROP 3 LASTPIN (-3350 2900) SIG_NAME M_F_CPU1_SB_DQS_DN<2>
J 0
(-3340 2910);
DISPLAY 0.659574 (-3340 2910);
PAINT MONO (-3340 2910);
DISPLAY INVISIBLE (-3340 2910);
FORCEPROP 1 LASTPIN (-3350 2900) BN 2
J 0
(-3362 2908);
DISPLAY 0.489362 (-3362 2908);
PAINT GREEN (-3362 2908);
FORCEPROP 2 LAST CDS_LIB mstr_standard
J 0
(-3300 2900);
DISPLAY 0.723404 (-3300 2900);
PAINT MONO (-3300 2900);
DISPLAY INVISIBLE (-3300 2900);
FORCEPROP 1 LAST BODY_TYPE PLUMBING
J 0
(-3300 2950);
DISPLAY 0.872340 (-3300 2950);
PAINT GREEN (-3300 2950);
DISPLAY INVISIBLE (-3300 2950);
FORCEPROP 1 LAST HDL_TAP TRUE
J 0
(-2975 2775);
DISPLAY 0.872340 (-2975 2775);
DISPLAY INVISIBLE (-2975 2775);
FORCEPROP 1 LAST PATH I226
J 0
(-3302 2900);
DISPLAY 0.872340 (-3302 2900);
PAINT GREEN (-3302 2900);
DISPLAY INVISIBLE (-3302 2900);
FORCEADD TAP..1
(-3500 3150);
FORCEPROP 3 LASTPIN (-3550 3150) SIG_NAME M_F_CPU1_SB_DQS_DP<4>
J 0
(-3540 3160);
DISPLAY 0.659574 (-3540 3160);
PAINT MONO (-3540 3160);
DISPLAY INVISIBLE (-3540 3160);
FORCEPROP 1 LASTPIN (-3550 3150) BN 4
J 0
(-3562 3158);
DISPLAY 0.489362 (-3562 3158);
PAINT GREEN (-3562 3158);
FORCEPROP 2 LAST CDS_LIB mstr_standard
J 0
(-3500 3150);
DISPLAY 0.723404 (-3500 3150);
PAINT MONO (-3500 3150);
DISPLAY INVISIBLE (-3500 3150);
FORCEPROP 1 LAST BODY_TYPE PLUMBING
J 0
(-3500 3200);
DISPLAY 0.872340 (-3500 3200);
PAINT GREEN (-3500 3200);
DISPLAY INVISIBLE (-3500 3200);
FORCEPROP 1 LAST HDL_TAP TRUE
J 0
(-3175 3025);
DISPLAY 0.872340 (-3175 3025);
DISPLAY INVISIBLE (-3175 3025);
FORCEPROP 1 LAST PATH I227
J 0
(-3502 3150);
DISPLAY 0.872340 (-3502 3150);
PAINT GREEN (-3502 3150);
DISPLAY INVISIBLE (-3502 3150);
FORCEADD TAP..1
(-3500 3350);
FORCEPROP 3 LASTPIN (-3550 3350) SIG_NAME M_F_CPU1_SB_DQS_DP<6>
J 0
(-3540 3360);
DISPLAY 0.659574 (-3540 3360);
PAINT MONO (-3540 3360);
DISPLAY INVISIBLE (-3540 3360);
FORCEPROP 1 LASTPIN (-3550 3350) BN 6
J 0
(-3562 3358);
DISPLAY 0.489362 (-3562 3358);
PAINT GREEN (-3562 3358);
FORCEPROP 2 LAST CDS_LIB mstr_standard
J 0
(-3500 3350);
DISPLAY 0.723404 (-3500 3350);
PAINT MONO (-3500 3350);
DISPLAY INVISIBLE (-3500 3350);
FORCEPROP 1 LAST BODY_TYPE PLUMBING
J 0
(-3500 3400);
DISPLAY 0.872340 (-3500 3400);
PAINT GREEN (-3500 3400);
DISPLAY INVISIBLE (-3500 3400);
FORCEPROP 1 LAST HDL_TAP TRUE
J 0
(-3175 3225);
DISPLAY 0.872340 (-3175 3225);
DISPLAY INVISIBLE (-3175 3225);
FORCEPROP 1 LAST PATH I228
J 0
(-3502 3350);
DISPLAY 0.872340 (-3502 3350);
PAINT GREEN (-3502 3350);
DISPLAY INVISIBLE (-3502 3350);
FORCEADD TAP..1
(-3500 3250);
FORCEPROP 3 LASTPIN (-3550 3250) SIG_NAME M_F_CPU1_SB_DQS_DP<5>
J 0
(-3540 3260);
DISPLAY 0.659574 (-3540 3260);
PAINT MONO (-3540 3260);
DISPLAY INVISIBLE (-3540 3260);
FORCEPROP 1 LASTPIN (-3550 3250) BN 5
J 0
(-3562 3258);
DISPLAY 0.489362 (-3562 3258);
PAINT GREEN (-3562 3258);
FORCEPROP 2 LAST CDS_LIB mstr_standard
J 0
(-3500 3250);
DISPLAY 0.723404 (-3500 3250);
PAINT MONO (-3500 3250);
DISPLAY INVISIBLE (-3500 3250);
FORCEPROP 1 LAST BODY_TYPE PLUMBING
J 0
(-3500 3300);
DISPLAY 0.872340 (-3500 3300);
PAINT GREEN (-3500 3300);
DISPLAY INVISIBLE (-3500 3300);
FORCEPROP 1 LAST HDL_TAP TRUE
J 0
(-3175 3125);
DISPLAY 0.872340 (-3175 3125);
DISPLAY INVISIBLE (-3175 3125);
FORCEPROP 1 LAST PATH I229
J 0
(-3502 3250);
DISPLAY 0.872340 (-3502 3250);
PAINT GREEN (-3502 3250);
DISPLAY INVISIBLE (-3502 3250);
FORCEADD TAP..1
R 2
(-7825 3325);
FORCEPROP 3 LASTPIN (-7775 3325) SIG_NAME M_F_CPU1_SB_CB<0>
J 0
(-7765 3335);
DISPLAY 0.659574 (-7765 3335);
PAINT MONO (-7765 3335);
DISPLAY INVISIBLE (-7765 3335);
FORCEPROP 1 LASTPIN (-7775 3325) BN 0
J 2
(-7763 3333);
DISPLAY 0.489362 (-7763 3333);
PAINT GREEN (-7763 3333);
FORCEPROP 2 LAST CDS_LIB mstr_standard
J 0
(-7825 3325);
DISPLAY 0.723404 (-7825 3325);
PAINT MONO (-7825 3325);
DISPLAY INVISIBLE (-7825 3325);
FORCEPROP 1 LAST BODY_TYPE PLUMBING
J 2
(-7825 3375);
DISPLAY 0.872340 (-7825 3375);
PAINT GREEN (-7825 3375);
DISPLAY INVISIBLE (-7825 3375);
FORCEPROP 1 LAST HDL_TAP TRUE
J 2
(-8150 3200);
DISPLAY 0.872340 (-8150 3200);
DISPLAY INVISIBLE (-8150 3200);
FORCEPROP 1 LAST PATH I23
J 2
(-7823 3325);
DISPLAY 0.872340 (-7823 3325);
PAINT GREEN (-7823 3325);
DISPLAY INVISIBLE (-7823 3325);
FORCEADD TAP..1
(-3500 2950);
FORCEPROP 3 LASTPIN (-3550 2950) SIG_NAME M_F_CPU1_SB_DQS_DP<2>
J 0
(-3540 2960);
DISPLAY 0.659574 (-3540 2960);
PAINT MONO (-3540 2960);
DISPLAY INVISIBLE (-3540 2960);
FORCEPROP 1 LASTPIN (-3550 2950) BN 2
J 0
(-3562 2958);
DISPLAY 0.489362 (-3562 2958);
PAINT GREEN (-3562 2958);
FORCEPROP 2 LAST CDS_LIB mstr_standard
J 0
(-3500 2950);
DISPLAY 0.723404 (-3500 2950);
PAINT MONO (-3500 2950);
DISPLAY INVISIBLE (-3500 2950);
FORCEPROP 1 LAST BODY_TYPE PLUMBING
J 0
(-3500 3000);
DISPLAY 0.872340 (-3500 3000);
PAINT GREEN (-3500 3000);
DISPLAY INVISIBLE (-3500 3000);
FORCEPROP 1 LAST HDL_TAP TRUE
J 0
(-3175 2825);
DISPLAY 0.872340 (-3175 2825);
DISPLAY INVISIBLE (-3175 2825);
FORCEPROP 1 LAST PATH I230
J 0
(-3502 2950);
DISPLAY 0.872340 (-3502 2950);
PAINT GREEN (-3502 2950);
DISPLAY INVISIBLE (-3502 2950);
FORCEADD TAP..1
(-3500 3050);
FORCEPROP 3 LASTPIN (-3550 3050) SIG_NAME M_F_CPU1_SB_DQS_DP<3>
J 0
(-3540 3060);
DISPLAY 0.659574 (-3540 3060);
PAINT MONO (-3540 3060);
DISPLAY INVISIBLE (-3540 3060);
FORCEPROP 1 LASTPIN (-3550 3050) BN 3
J 0
(-3562 3058);
DISPLAY 0.489362 (-3562 3058);
PAINT GREEN (-3562 3058);
FORCEPROP 2 LAST CDS_LIB mstr_standard
J 0
(-3500 3050);
DISPLAY 0.723404 (-3500 3050);
PAINT MONO (-3500 3050);
DISPLAY INVISIBLE (-3500 3050);
FORCEPROP 1 LAST BODY_TYPE PLUMBING
J 0
(-3500 3100);
DISPLAY 0.872340 (-3500 3100);
PAINT GREEN (-3500 3100);
DISPLAY INVISIBLE (-3500 3100);
FORCEPROP 1 LAST HDL_TAP TRUE
J 0
(-3175 2925);
DISPLAY 0.872340 (-3175 2925);
DISPLAY INVISIBLE (-3175 2925);
FORCEPROP 1 LAST PATH I231
J 0
(-3502 3050);
DISPLAY 0.872340 (-3502 3050);
PAINT GREEN (-3502 3050);
DISPLAY INVISIBLE (-3502 3050);
FORCEADD TAP..1
(-3300 2800);
FORCEPROP 3 LASTPIN (-3350 2800) SIG_NAME M_F_CPU1_SB_DQS_DN<1>
J 0
(-3340 2810);
DISPLAY 0.659574 (-3340 2810);
PAINT MONO (-3340 2810);
DISPLAY INVISIBLE (-3340 2810);
FORCEPROP 1 LASTPIN (-3350 2800) BN 1
J 0
(-3362 2808);
DISPLAY 0.489362 (-3362 2808);
PAINT GREEN (-3362 2808);
FORCEPROP 2 LAST CDS_LIB mstr_standard
J 0
(-3300 2800);
DISPLAY 0.723404 (-3300 2800);
PAINT MONO (-3300 2800);
DISPLAY INVISIBLE (-3300 2800);
FORCEPROP 1 LAST BODY_TYPE PLUMBING
J 0
(-3300 2850);
DISPLAY 0.872340 (-3300 2850);
PAINT GREEN (-3300 2850);
DISPLAY INVISIBLE (-3300 2850);
FORCEPROP 1 LAST HDL_TAP TRUE
J 0
(-2975 2675);
DISPLAY 0.872340 (-2975 2675);
DISPLAY INVISIBLE (-2975 2675);
FORCEPROP 1 LAST PATH I232
J 0
(-3302 2800);
DISPLAY 0.872340 (-3302 2800);
PAINT GREEN (-3302 2800);
DISPLAY INVISIBLE (-3302 2800);
FORCEADD TAP..1
(-3300 2700);
FORCEPROP 3 LASTPIN (-3350 2700) SIG_NAME M_F_CPU1_SB_DQS_DN<0>
J 0
(-3340 2710);
DISPLAY 0.659574 (-3340 2710);
PAINT MONO (-3340 2710);
DISPLAY INVISIBLE (-3340 2710);
FORCEPROP 1 LASTPIN (-3350 2700) BN 0
J 0
(-3362 2708);
DISPLAY 0.489362 (-3362 2708);
PAINT GREEN (-3362 2708);
FORCEPROP 2 LAST CDS_LIB mstr_standard
J 0
(-3300 2700);
DISPLAY 0.723404 (-3300 2700);
PAINT MONO (-3300 2700);
DISPLAY INVISIBLE (-3300 2700);
FORCEPROP 1 LAST BODY_TYPE PLUMBING
J 0
(-3300 2750);
DISPLAY 0.872340 (-3300 2750);
PAINT GREEN (-3300 2750);
DISPLAY INVISIBLE (-3300 2750);
FORCEPROP 1 LAST HDL_TAP TRUE
J 0
(-2975 2575);
DISPLAY 0.872340 (-2975 2575);
DISPLAY INVISIBLE (-2975 2575);
FORCEPROP 1 LAST PATH I233
J 0
(-3302 2700);
DISPLAY 0.872340 (-3302 2700);
PAINT GREEN (-3302 2700);
DISPLAY INVISIBLE (-3302 2700);
FORCEADD TAP..1
(-3500 2750);
FORCEPROP 3 LASTPIN (-3550 2750) SIG_NAME M_F_CPU1_SB_DQS_DP<0>
J 0
(-3540 2760);
DISPLAY 0.659574 (-3540 2760);
PAINT MONO (-3540 2760);
DISPLAY INVISIBLE (-3540 2760);
FORCEPROP 1 LASTPIN (-3550 2750) BN 0
J 0
(-3562 2758);
DISPLAY 0.489362 (-3562 2758);
PAINT GREEN (-3562 2758);
FORCEPROP 2 LAST CDS_LIB mstr_standard
J 0
(-3500 2750);
DISPLAY 0.723404 (-3500 2750);
PAINT MONO (-3500 2750);
DISPLAY INVISIBLE (-3500 2750);
FORCEPROP 1 LAST BODY_TYPE PLUMBING
J 0
(-3500 2800);
DISPLAY 0.872340 (-3500 2800);
PAINT GREEN (-3500 2800);
DISPLAY INVISIBLE (-3500 2800);
FORCEPROP 1 LAST HDL_TAP TRUE
J 0
(-3175 2625);
DISPLAY 0.872340 (-3175 2625);
DISPLAY INVISIBLE (-3175 2625);
FORCEPROP 1 LAST PATH I234
J 0
(-3502 2750);
DISPLAY 0.872340 (-3502 2750);
PAINT GREEN (-3502 2750);
DISPLAY INVISIBLE (-3502 2750);
FORCEADD TAP..1
(-3500 2850);
FORCEPROP 3 LASTPIN (-3550 2850) SIG_NAME M_F_CPU1_SB_DQS_DP<1>
J 0
(-3540 2860);
DISPLAY 0.659574 (-3540 2860);
PAINT MONO (-3540 2860);
DISPLAY INVISIBLE (-3540 2860);
FORCEPROP 1 LASTPIN (-3550 2850) BN 1
J 0
(-3562 2858);
DISPLAY 0.489362 (-3562 2858);
PAINT GREEN (-3562 2858);
FORCEPROP 2 LAST CDS_LIB mstr_standard
J 0
(-3500 2850);
DISPLAY 0.723404 (-3500 2850);
PAINT MONO (-3500 2850);
DISPLAY INVISIBLE (-3500 2850);
FORCEPROP 1 LAST BODY_TYPE PLUMBING
J 0
(-3500 2900);
DISPLAY 0.872340 (-3500 2900);
PAINT GREEN (-3500 2900);
DISPLAY INVISIBLE (-3500 2900);
FORCEPROP 1 LAST HDL_TAP TRUE
J 0
(-3175 2725);
DISPLAY 0.872340 (-3175 2725);
DISPLAY INVISIBLE (-3175 2725);
FORCEPROP 1 LAST PATH I235
J 0
(-3502 2850);
DISPLAY 0.872340 (-3502 2850);
PAINT GREEN (-3502 2850);
DISPLAY INVISIBLE (-3502 2850);
FORCEADD SCONN288_DDR506112002KQ..2
(-4450 3700);
FORCEPROP 1 LAST LOCATION J33
J 0
(-5050 5025);
DISPLAY 0.468085 (-5050 5025);
PAINT SKYBLUE (-5050 5025);
FORCEPROP 0 LAST $SEC 2
J 0
(-4900 5175);
DISPLAY 0.680851 (-4900 5175);
PAINT MONO (-4900 5175);
DISPLAY INVISIBLE (-4900 5175);
FORCEPROP 0 LAST CDS_SEC 2
J 0
(-4900 5175);
DISPLAY 1.021277 (-4900 5175);
DISPLAY INVISIBLE (-4900 5175);
FORCEPROP 0 LASTPIN (-3700 3750) $PN 12
J 0
(-3690 3760);
DISPLAY 0.680851 (-3690 3760);
PAINT MONO (-3690 3760);
FORCEPROP 0 LASTPIN (-3700 3800) $PN 11
J 0
(-3690 3810);
DISPLAY 0.680851 (-3690 3810);
PAINT MONO (-3690 3810);
FORCEPROP 0 LASTPIN (-3700 2700) $PN 105
J 0
(-3690 2710);
DISPLAY 0.680851 (-3690 2710);
PAINT MONO (-3690 2710);
FORCEPROP 0 LASTPIN (-3700 2750) $PN 104
J 0
(-3690 2760);
DISPLAY 0.680851 (-3690 2760);
PAINT MONO (-3690 2760);
FORCEPROP 0 LASTPIN (-3700 3850) $PN 23
J 0
(-3690 3860);
DISPLAY 0.680851 (-3690 3860);
PAINT MONO (-3690 3860);
FORCEPROP 0 LASTPIN (-3700 3900) $PN 22
J 0
(-3690 3910);
DISPLAY 0.680851 (-3690 3910);
PAINT MONO (-3690 3910);
FORCEPROP 0 LASTPIN (-3700 2800) $PN 116
J 0
(-3690 2810);
DISPLAY 0.680851 (-3690 2810);
PAINT MONO (-3690 2810);
FORCEPROP 0 LASTPIN (-3700 2850) $PN 115
J 0
(-3690 2860);
DISPLAY 0.680851 (-3690 2860);
PAINT MONO (-3690 2860);
FORCEPROP 0 LASTPIN (-3700 3950) $PN 34
J 0
(-3690 3960);
DISPLAY 0.680851 (-3690 3960);
PAINT MONO (-3690 3960);
FORCEPROP 0 LASTPIN (-3700 4000) $PN 33
J 0
(-3690 4010);
DISPLAY 0.680851 (-3690 4010);
PAINT MONO (-3690 4010);
FORCEPROP 0 LASTPIN (-3700 2900) $PN 127
J 0
(-3690 2910);
DISPLAY 0.680851 (-3690 2910);
PAINT MONO (-3690 2910);
FORCEPROP 0 LASTPIN (-3700 2950) $PN 126
J 0
(-3690 2960);
DISPLAY 0.680851 (-3690 2960);
PAINT MONO (-3690 2960);
FORCEPROP 0 LASTPIN (-3700 4050) $PN 45
J 0
(-3690 4060);
DISPLAY 0.680851 (-3690 4060);
PAINT MONO (-3690 4060);
FORCEPROP 0 LASTPIN (-3700 4100) $PN 44
J 0
(-3690 4110);
DISPLAY 0.680851 (-3690 4110);
PAINT MONO (-3690 4110);
FORCEPROP 0 LASTPIN (-3700 3000) $PN 138
J 0
(-3690 3010);
DISPLAY 0.680851 (-3690 3010);
PAINT MONO (-3690 3010);
FORCEPROP 0 LASTPIN (-3700 3050) $PN 137
J 0
(-3690 3060);
DISPLAY 0.680851 (-3690 3060);
PAINT MONO (-3690 3060);
FORCEPROP 0 LASTPIN (-3700 4150) $PN 56
J 0
(-3690 4160);
DISPLAY 0.680851 (-3690 4160);
PAINT MONO (-3690 4160);
FORCEPROP 0 LASTPIN (-3700 4200) $PN 55
J 0
(-3690 4210);
DISPLAY 0.680851 (-3690 4210);
PAINT MONO (-3690 4210);
FORCEPROP 0 LASTPIN (-3700 3100) $PN 238
J 0
(-3690 3110);
DISPLAY 0.680851 (-3690 3110);
PAINT MONO (-3690 3110);
FORCEPROP 0 LASTPIN (-3700 3150) $PN 239
J 0
(-3690 3160);
DISPLAY 0.680851 (-3690 3160);
PAINT MONO (-3690 3160);
FORCEPROP 0 LASTPIN (-3700 4250) $PN 156
J 0
(-3690 4260);
DISPLAY 0.680851 (-3690 4260);
PAINT MONO (-3690 4260);
FORCEPROP 0 LASTPIN (-3700 4300) $PN 157
J 0
(-3690 4310);
DISPLAY 0.680851 (-3690 4310);
PAINT MONO (-3690 4310);
FORCEPROP 0 LASTPIN (-3700 3200) $PN 249
J 0
(-3690 3210);
DISPLAY 0.680851 (-3690 3210);
PAINT MONO (-3690 3210);
FORCEPROP 0 LASTPIN (-3700 3250) $PN 250
J 0
(-3690 3260);
DISPLAY 0.680851 (-3690 3260);
PAINT MONO (-3690 3260);
FORCEPROP 0 LASTPIN (-3700 4350) $PN 167
J 0
(-3690 4360);
DISPLAY 0.680851 (-3690 4360);
PAINT MONO (-3690 4360);
FORCEPROP 0 LASTPIN (-3700 4400) $PN 168
J 0
(-3690 4410);
DISPLAY 0.680851 (-3690 4410);
PAINT MONO (-3690 4410);
FORCEPROP 0 LASTPIN (-3700 3300) $PN 260
J 0
(-3690 3310);
DISPLAY 0.680851 (-3690 3310);
PAINT MONO (-3690 3310);
FORCEPROP 0 LASTPIN (-3700 3350) $PN 261
J 0
(-3690 3360);
DISPLAY 0.680851 (-3690 3360);
PAINT MONO (-3690 3360);
FORCEPROP 0 LASTPIN (-3700 4450) $PN 178
J 0
(-3690 4460);
DISPLAY 0.680851 (-3690 4460);
PAINT MONO (-3690 4460);
FORCEPROP 0 LASTPIN (-3700 4500) $PN 179
J 0
(-3690 4510);
DISPLAY 0.680851 (-3690 4510);
PAINT MONO (-3690 4510);
FORCEPROP 0 LASTPIN (-3700 3400) $PN 271
J 0
(-3690 3410);
DISPLAY 0.680851 (-3690 3410);
PAINT MONO (-3690 3410);
FORCEPROP 0 LASTPIN (-3700 3450) $PN 272
J 0
(-3690 3460);
DISPLAY 0.680851 (-3690 3460);
PAINT MONO (-3690 3460);
FORCEPROP 0 LASTPIN (-3700 4550) $PN 189
J 0
(-3690 4560);
DISPLAY 0.680851 (-3690 4560);
PAINT MONO (-3690 4560);
FORCEPROP 0 LASTPIN (-3700 4600) $PN 190
J 0
(-3690 4610);
DISPLAY 0.680851 (-3690 4610);
PAINT MONO (-3690 4610);
FORCEPROP 0 LASTPIN (-3700 3500) $PN 282
J 0
(-3690 3510);
DISPLAY 0.680851 (-3690 3510);
PAINT MONO (-3690 3510);
FORCEPROP 0 LASTPIN (-3700 3550) $PN 283
J 0
(-3690 3560);
DISPLAY 0.680851 (-3690 3560);
PAINT MONO (-3690 3560);
FORCEPROP 0 LASTPIN (-3700 4650) $PN 200
J 0
(-3690 4660);
DISPLAY 0.680851 (-3690 4660);
PAINT MONO (-3690 4660);
FORCEPROP 0 LASTPIN (-3700 4700) $PN 201
J 0
(-3690 4710);
DISPLAY 0.680851 (-3690 4710);
PAINT MONO (-3690 4710);
FORCEPROP 0 LASTPIN (-3700 3600) $PN 94
J 0
(-3690 3610);
DISPLAY 0.680851 (-3690 3610);
PAINT MONO (-3690 3610);
FORCEPROP 0 LASTPIN (-3700 3650) $PN 93
J 0
(-3690 3660);
DISPLAY 0.680851 (-3690 3660);
PAINT MONO (-3690 3660);
FORCEPROP 2 LAST VALUE SCONN288_DDR506112002KQ
J 0
(-4900 5075);
DISPLAY 0.489362 (-4900 5075);
PAINT SKYBLUE (-4900 5075);
FORCEPROP 1 LAST MATERIAL IO
J 0
(-5050 4875);
DISPLAY 0.468085 (-5050 4875);
PAINT SKYBLUE (-5050 4875);
FORCEPROP 2 LAST PART_TYPE SMLF
J 0
(-4900 5125);
DISPLAY 1.021277 (-4900 5125);
FORCEPROP 1 LAST CDS_LMAN_SYM_OUTLINE -600,1150,600,-1150
J 0
(-4450 3700);
DISPLAY 0.468085 (-4450 3700);
PAINT GREEN (-4450 3700);
DISPLAY INVISIBLE (-4450 3700);
FORCEPROP 1 LAST NEEDS_NO_SIZE TRUE
J 0
(-4450 3700);
DISPLAY 0.723404 (-4450 3700);
PAINT GREEN (-4450 3700);
DISPLAY INVISIBLE (-4450 3700);
FORCEPROP 2 LAST CDS_LIB pure_quanta
J 0
(-4450 3700);
DISPLAY INVISIBLE (-4450 3700);
FORCEPROP 1 LAST PATH I236
J 0
(-4450 3700);
DISPLAY 0.723404 (-4450 3700);
PAINT GREEN (-4450 3700);
DISPLAY INVISIBLE (-4450 3700);
FORCEPROP 1 LAST PART_NUMBER DFHST8FS479
J 0
(-5050 4950);
DISPLAY 0.468085 (-5050 4950);
PAINT SKYBLUE (-5050 4950);
DISPLAY INVISIBLE (-5050 4950);
FORCEADD GND..1
(-2900 5650);
FORCEPROP 3 LASTPIN (-2900 5700) SIG_NAME GND\g
J 0
(-2890 5710);
DISPLAY 0.659574 (-2890 5710);
PAINT MONO (-2890 5710);
DISPLAY INVISIBLE (-2890 5710);
FORCEPROP 2 LAST CDS_LIB pure_quanta_power
J 0
(-2900 5650);
DISPLAY INVISIBLE (-2900 5650);
FORCEPROP 2 LAST BOM_COST MEM
J 0
(-2875 5775);
DISPLAY 0.659574 (-2875 5775);
DISPLAY INVISIBLE (-2875 5775);
FORCEPROP 1 LAST SIZE 1B
J 0
(-2825 5600);
DISPLAY 0.723404 (-2825 5600);
PAINT GREEN (-2825 5600);
DISPLAY INVISIBLE (-2825 5600);
FORCEPROP 2 LAST ROOM MEM_EFGH_DECOUPLING_CAPS
J 0
(-2875 5725);
DISPLAY 0.659574 (-2875 5725);
PAINT RED (-2875 5725);
DISPLAY INVISIBLE (-2875 5725);
FORCEPROP 1 LAST HDL_POWER GND
J 0
(-2900 5800);
DISPLAY 0.723404 (-2900 5800);
PAINT GREEN (-2900 5800);
DISPLAY INVISIBLE (-2900 5800);
FORCEPROP 1 LAST PATH I237
J 0
(-2825 5650);
DISPLAY 0.872340 (-2825 5650);
PAINT AQUA (-2825 5650);
DISPLAY INVISIBLE (-2825 5650);
FORCEADD Q_CAP..1
R 2
(-2900 6000);
FORCEPROP 1 LAST LOCATION C518
J 2
(-2950 6100);
DISPLAY 0.489362 (-2950 6100);
PAINT SKYBLUE (-2950 6100);
FORCEPROP 0 LAST $SEC 1
J 0
(-2950 6150);
DISPLAY 0.680851 (-2950 6150);
PAINT MONO (-2950 6150);
DISPLAY INVISIBLE (-2950 6150);
FORCEPROP 0 LAST CDS_SEC 1
J 0
(-2950 6150);
DISPLAY 0.680851 (-2950 6150);
DISPLAY INVISIBLE (-2950 6150);
FORCEPROP 1 LASTPIN (-2900 6100) $PN 1
J 2
(-2910 6080);
DISPLAY 0.489362 (-2910 6080);
PAINT MONO (-2910 6080);
FORCEPROP 1 LASTPIN (-2900 5900) $PN 2
J 2
(-2910 5880);
DISPLAY 0.489362 (-2910 5880);
PAINT MONO (-2910 5880);
FORCEPROP 1 LAST PACK_TYPE C0805
J 2
(-2950 5800);
DISPLAY 0.489362 (-2950 5800);
PAINT SKYBLUE (-2950 5800);
FORCEPROP 1 LAST VOLTAGE 25V
J 2
(-2950 6000);
DISPLAY 0.489362 (-2950 6000);
PAINT SKYBLUE (-2950 6000);
FORCEPROP 1 LAST VALUE 10UF
J 2
(-2950 6050);
DISPLAY 0.489362 (-2950 6050);
PAINT SKYBLUE (-2950 6050);
FORCEPROP 1 LAST TOLERANCE 10%
J 2
(-2950 5950);
DISPLAY 0.489362 (-2950 5950);
PAINT SKYBLUE (-2950 5950);
FORCEPROP 1 LAST MATERIAL X6S
J 2
(-2950 5900);
DISPLAY 0.489362 (-2950 5900);
PAINT SKYBLUE (-2950 5900);
FORCEPROP 2 LAST CDS_LIB pure_quanta
J 0
(-2900 6000);
DISPLAY INVISIBLE (-2900 6000);
FORCEPROP 0 LAST BOM_COST MEM
J 2
(-2955 6145);
DISPLAY 0.595745 (-2955 6145);
PAINT MONO (-2955 6145);
DISPLAY INVISIBLE (-2955 6145);
FORCEPROP 2 LAST ROOM 
J 2
(-2955 6145);
DISPLAY 0.595745 (-2955 6145);
PAINT RED (-2955 6145);
DISPLAY INVISIBLE (-2955 6145);
FORCEPROP 1 LAST PATH I238
J 2
(-2950 6150);
DISPLAY 0.978723 (-2950 6150);
PAINT WHITE (-2950 6150);
DISPLAY INVISIBLE (-2950 6150);
FORCEPROP 1 LAST PART_NUMBER CH6104KEA00
J 2
(-2950 5850);
DISPLAY 0.489362 (-2950 5850);
PAINT SKYBLUE (-2950 5850);
DISPLAY INVISIBLE (-2950 5850);
FORCEADD Q_CAP..1
R 2
(-2325 6000);
FORCEPROP 1 LAST LOCATION C527
J 2
(-2375 6100);
DISPLAY 0.489362 (-2375 6100);
PAINT SKYBLUE (-2375 6100);
FORCEPROP 0 LAST $SEC 1
J 0
(-2375 6150);
DISPLAY 0.680851 (-2375 6150);
PAINT MONO (-2375 6150);
DISPLAY INVISIBLE (-2375 6150);
FORCEPROP 0 LAST CDS_SEC 1
J 0
(-2375 6150);
DISPLAY 0.680851 (-2375 6150);
DISPLAY INVISIBLE (-2375 6150);
FORCEPROP 1 LASTPIN (-2325 6100) $PN 1
J 2
(-2335 6080);
DISPLAY 0.489362 (-2335 6080);
PAINT MONO (-2335 6080);
FORCEPROP 1 LASTPIN (-2325 5900) $PN 2
J 2
(-2335 5880);
DISPLAY 0.489362 (-2335 5880);
PAINT MONO (-2335 5880);
FORCEPROP 1 LAST PACK_TYPE C0805
J 2
(-2375 5800);
DISPLAY 0.489362 (-2375 5800);
PAINT SKYBLUE (-2375 5800);
FORCEPROP 1 LAST VOLTAGE 25V
J 2
(-2375 6000);
DISPLAY 0.489362 (-2375 6000);
PAINT SKYBLUE (-2375 6000);
FORCEPROP 1 LAST VALUE 10UF
J 2
(-2375 6050);
DISPLAY 0.489362 (-2375 6050);
PAINT SKYBLUE (-2375 6050);
FORCEPROP 1 LAST TOLERANCE 10%
J 2
(-2375 5950);
DISPLAY 0.489362 (-2375 5950);
PAINT SKYBLUE (-2375 5950);
FORCEPROP 1 LAST MATERIAL X6S
J 2
(-2375 5900);
DISPLAY 0.489362 (-2375 5900);
PAINT SKYBLUE (-2375 5900);
FORCEPROP 2 LAST CDS_LIB pure_quanta
J 0
(-2325 6000);
DISPLAY INVISIBLE (-2325 6000);
FORCEPROP 0 LAST BOM_COST MEM
J 2
(-2380 6145);
DISPLAY 0.595745 (-2380 6145);
PAINT MONO (-2380 6145);
DISPLAY INVISIBLE (-2380 6145);
FORCEPROP 2 LAST ROOM 
J 2
(-2380 6145);
DISPLAY 0.595745 (-2380 6145);
PAINT RED (-2380 6145);
DISPLAY INVISIBLE (-2380 6145);
FORCEPROP 1 LAST PATH I239
J 2
(-2375 6150);
DISPLAY 0.978723 (-2375 6150);
PAINT WHITE (-2375 6150);
DISPLAY INVISIBLE (-2375 6150);
FORCEPROP 1 LAST PART_NUMBER CH6104KEA00
J 2
(-2375 5850);
DISPLAY 0.489362 (-2375 5850);
PAINT SKYBLUE (-2375 5850);
DISPLAY INVISIBLE (-2375 5850);
FORCEADD TAP..1
R 2
(-7825 3375);
FORCEPROP 3 LASTPIN (-7775 3375) SIG_NAME M_F_CPU1_SB_CB<1>
J 0
(-7765 3385);
DISPLAY 0.659574 (-7765 3385);
PAINT MONO (-7765 3385);
DISPLAY INVISIBLE (-7765 3385);
FORCEPROP 1 LASTPIN (-7775 3375) BN 1
J 2
(-7763 3383);
DISPLAY 0.489362 (-7763 3383);
PAINT GREEN (-7763 3383);
FORCEPROP 2 LAST CDS_LIB mstr_standard
J 0
(-7825 3375);
DISPLAY 0.723404 (-7825 3375);
PAINT MONO (-7825 3375);
DISPLAY INVISIBLE (-7825 3375);
FORCEPROP 1 LAST BODY_TYPE PLUMBING
J 2
(-7825 3425);
DISPLAY 0.872340 (-7825 3425);
PAINT GREEN (-7825 3425);
DISPLAY INVISIBLE (-7825 3425);
FORCEPROP 1 LAST HDL_TAP TRUE
J 2
(-8150 3250);
DISPLAY 0.872340 (-8150 3250);
DISPLAY INVISIBLE (-8150 3250);
FORCEPROP 1 LAST PATH I24
J 2
(-7823 3375);
DISPLAY 0.872340 (-7823 3375);
PAINT GREEN (-7823 3375);
DISPLAY INVISIBLE (-7823 3375);
FORCEADD UNIVERSAL_POWER..1
(-2900 6325);
FORCEPROP 3 LASTPIN (-2900 6275) SIG_NAME P12V_MEM_CPU1\g
J 0
(-2890 6285);
DISPLAY 0.659574 (-2890 6285);
PAINT MONO (-2890 6285);
DISPLAY INVISIBLE (-2890 6285);
FORCEPROP 1 LAST HDL_POWER P12V_MEM_CPU1
J 1
(-2900 6375);
DISPLAY 0.489362 (-2900 6375);
PAINT GREEN (-2900 6375);
FORCEPROP 2 LAST CDS_LIB pure_quanta_power
J 0
(-2900 6325);
DISPLAY INVISIBLE (-2900 6325);
FORCEPROP 1 LAST PATH I240
J 0
(-2850 6350);
DISPLAY 0.872340 (-2850 6350);
PAINT AQUA (-2850 6350);
DISPLAY INVISIBLE (-2850 6350);
FORCEADD OFFPAGE..1
(-8550 2750);
FORCEPROP 2 LAST $XR5 102 
J 0
(-9342 2750);
DISPLAY 0.638298 (-9342 2750);
PAINT MONO (-9342 2750);
FORCEPROP 2 LAST $XR4 101 
J 0
(-9222 2750);
DISPLAY 0.638298 (-9222 2750);
PAINT MONO (-9222 2750);
FORCEPROP 2 LAST $XR3 100 
J 0
(-9102 2750);
DISPLAY 0.638298 (-9102 2750);
PAINT MONO (-9102 2750);
FORCEPROP 2 LAST $XR2 99 
J 0
(-8982 2750);
DISPLAY 0.638298 (-8982 2750);
PAINT MONO (-8982 2750);
FORCEPROP 2 LAST $XR1 98 
J 0
(-8892 2750);
DISPLAY 0.638298 (-8892 2750);
PAINT MONO (-8892 2750);
FORCEPROP 2 LAST $XR0 159 
J 0
(-8802 2750);
DISPLAY 0.638298 (-8802 2750);
PAINT MONO (-8802 2750);
FORCEPROP 2 LAST CDS_LIB mstr_standard
J 0
(-8550 2750);
DISPLAY 0.808511 (-8550 2750);
DISPLAY INVISIBLE (-8550 2750);
FORCEPROP 1 LAST OFFPAGE TRUE
J 0
(-8225 2625);
DISPLAY 0.872340 (-8225 2625);
PAINT GREEN (-8225 2625);
DISPLAY INVISIBLE (-8225 2625);
FORCEPROP 1 LAST COMMENT_BODY TRUE
J 0
(-8425 2650);
DISPLAY 0.872340 (-8425 2650);
PAINT GREEN (-8425 2650);
DISPLAY INVISIBLE (-8425 2650);
FORCEPROP 2 LAST PATH I241
J 0
(-8825 2800);
DISPLAY 0.680851 (-8825 2800);
DISPLAY INVISIBLE (-8825 2800);
FORCEADD Q_RES..1
(-7850 2750);
FORCEPROP 1 LAST LOCATION R1585
J 0
(-7900 2775);
DISPLAY 0.510638 (-7900 2775);
PAINT SKYBLUE (-7900 2775);
FORCEPROP 0 LAST $SEC 1
J 0
(-7900 2850);
DISPLAY 0.680851 (-7900 2850);
PAINT MONO (-7900 2850);
DISPLAY INVISIBLE (-7900 2850);
FORCEPROP 0 LAST CDS_SEC 1
J 0
(-7900 2850);
DISPLAY 0.680851 (-7900 2850);
DISPLAY INVISIBLE (-7900 2850);
FORCEPROP 1 LASTPIN (-7950 2750) $PN 1
J 0
(-7938 2762);
DISPLAY 0.787234 (-7938 2762);
PAINT MONO (-7938 2762);
FORCEPROP 1 LASTPIN (-7750 2750) $PN 2
J 0
(-7788 2762);
DISPLAY 0.787234 (-7788 2762);
PAINT MONO (-7788 2762);
FORCEPROP 1 LAST VALUE 49.9
J 2
(-7700 2800);
DISPLAY 0.510638 (-7700 2800);
PAINT SKYBLUE (-7700 2800);
FORCEPROP 2 LAST CDS_LIB pure_quanta
J 0
(-7850 2750);
DISPLAY INVISIBLE (-7850 2750);
FORCEPROP 1 LAST MATERIAL CHIP
J 0
(-7850 2600);
DISPLAY 0.978723 (-7850 2600);
DISPLAY INVISIBLE (-7850 2600);
FORCEPROP 1 LAST PACK_TYPE 0402LF
J 0
(-7600 2600);
DISPLAY 0.978723 (-7600 2600);
DISPLAY INVISIBLE (-7600 2600);
FORCEPROP 1 LAST WATTAGE 1/16W
J 2
(-7875 2600);
DISPLAY 0.978723 (-7875 2600);
DISPLAY INVISIBLE (-7875 2600);
FORCEPROP 1 LAST TOLERANCE 1%
J 0
(-7850 2650);
DISPLAY 0.978723 (-7850 2650);
DISPLAY INVISIBLE (-7850 2650);
FORCEPROP 1 LAST PATH I242
J 0
(-7900 2900);
DISPLAY 0.978723 (-7900 2900);
PAINT WHITE (-7900 2900);
DISPLAY INVISIBLE (-7900 2900);
FORCEPROP 1 LAST PART_NUMBER CS04992FB07
J 0
(-7900 2850);
DISPLAY 0.978723 (-7900 2850);
DISPLAY INVISIBLE (-7900 2850);
FORCEADD Q_RES..1
(-8250 2975);
FORCEPROP 1 LAST LOCATION R1704
J 0
(-8450 2975);
DISPLAY 0.638298 (-8450 2975);
FORCEPROP 0 LAST $SEC 1
J 0
(-8400 3025);
DISPLAY 0.680851 (-8400 3025);
PAINT MONO (-8400 3025);
DISPLAY INVISIBLE (-8400 3025);
FORCEPROP 0 LAST CDS_SEC 1
J 0
(-8400 3025);
DISPLAY 0.680851 (-8400 3025);
DISPLAY INVISIBLE (-8400 3025);
FORCEPROP 1 LASTPIN (-8350 2975) $PN 1
J 0
(-8338 2987);
DISPLAY 0.787234 (-8338 2987);
PAINT MONO (-8338 2987);
FORCEPROP 1 LASTPIN (-8150 2975) $PN 2
J 0
(-8188 2987);
DISPLAY 0.787234 (-8188 2987);
PAINT MONO (-8188 2987);
FORCEPROP 1 LAST PACK_TYPE 0402LF
J 0
(-8200 2950);
DISPLAY 0.404255 (-8200 2950);
FORCEPROP 1 LAST MATERIAL CHIP
J 0
(-8350 2950);
DISPLAY 0.404255 (-8350 2950);
FORCEPROP 1 LAST VALUE 10
J 2
(-8100 2975);
DISPLAY 0.404255 (-8100 2975);
FORCEPROP 2 LAST CDS_LIB pure_quanta
J 0
(-8250 2975);
DISPLAY INVISIBLE (-8250 2975);
FORCEPROP 1 LAST TOLERANCE 1%
J 0
(-8250 2875);
DISPLAY 0.978723 (-8250 2875);
DISPLAY INVISIBLE (-8250 2875);
FORCEPROP 1 LAST WATTAGE 1/16W
J 2
(-8275 2825);
DISPLAY 0.978723 (-8275 2825);
DISPLAY INVISIBLE (-8275 2825);
FORCEPROP 1 LAST PATH I243
J 0
(-8300 3125);
DISPLAY 0.978723 (-8300 3125);
PAINT WHITE (-8300 3125);
DISPLAY INVISIBLE (-8300 3125);
FORCEPROP 1 LAST PART_NUMBER CS01002FB07
J 0
(-8300 3075);
DISPLAY 0.978723 (-8300 3075);
DISPLAY INVISIBLE (-8300 3075);
FORCEADD OFFPAGE..6
(-8900 2850);
FORCEPROP 2 LAST $XR5 159 
J 0
(-9239 2886);
DISPLAY 0.638298 (-9239 2886);
PAINT MONO (-9239 2886);
FORCEPROP 2 LAST $XR4 102 
J 0
(-9359 2814);
DISPLAY 0.638298 (-9359 2814);
PAINT MONO (-9359 2814);
FORCEPROP 2 LAST $XR3 101 
J 0
(-9239 2814);
DISPLAY 0.638298 (-9239 2814);
PAINT MONO (-9239 2814);
FORCEPROP 2 LAST $XR2 100 
J 0
(-9359 2850);
DISPLAY 0.638298 (-9359 2850);
PAINT MONO (-9359 2850);
FORCEPROP 2 LAST $XR1 99 
J 0
(-9239 2850);
DISPLAY 0.638298 (-9239 2850);
PAINT MONO (-9239 2850);
FORCEPROP 2 LAST $XR0 98 
J 0
(-9149 2850);
DISPLAY 0.638298 (-9149 2850);
PAINT MONO (-9149 2850);
FORCEPROP 2 LAST CDS_LIB mstr_standard
J 0
(-8900 2850);
DISPLAY 0.808511 (-8900 2850);
DISPLAY INVISIBLE (-8900 2850);
FORCEPROP 1 LAST OFFPAGE TRUE
J 0
(-8575 2725);
DISPLAY 0.872340 (-8575 2725);
PAINT GREEN (-8575 2725);
DISPLAY INVISIBLE (-8575 2725);
FORCEPROP 1 LAST COMMENT_BODY TRUE
J 0
(-8800 2775);
DISPLAY 0.872340 (-8800 2775);
PAINT GREEN (-8800 2775);
DISPLAY INVISIBLE (-8800 2775);
FORCEPROP 2 LAST PATH I244
J 0
(-9125 2900);
DISPLAY 0.680851 (-9125 2900);
DISPLAY INVISIBLE (-9125 2900);
FORCEADD TAP..1
R 2
(-7825 3425);
FORCEPROP 3 LASTPIN (-7775 3425) SIG_NAME M_F_CPU1_SB_CB<2>
J 0
(-7765 3435);
DISPLAY 0.659574 (-7765 3435);
PAINT MONO (-7765 3435);
DISPLAY INVISIBLE (-7765 3435);
FORCEPROP 1 LASTPIN (-7775 3425) BN 2
J 2
(-7763 3433);
DISPLAY 0.489362 (-7763 3433);
PAINT GREEN (-7763 3433);
FORCEPROP 2 LAST CDS_LIB mstr_standard
J 0
(-7825 3425);
DISPLAY 0.723404 (-7825 3425);
PAINT MONO (-7825 3425);
DISPLAY INVISIBLE (-7825 3425);
FORCEPROP 1 LAST BODY_TYPE PLUMBING
J 2
(-7825 3475);
DISPLAY 0.872340 (-7825 3475);
PAINT GREEN (-7825 3475);
DISPLAY INVISIBLE (-7825 3475);
FORCEPROP 1 LAST HDL_TAP TRUE
J 2
(-8150 3300);
DISPLAY 0.872340 (-8150 3300);
DISPLAY INVISIBLE (-8150 3300);
FORCEPROP 1 LAST PATH I25
J 2
(-7823 3425);
DISPLAY 0.872340 (-7823 3425);
PAINT GREEN (-7823 3425);
DISPLAY INVISIBLE (-7823 3425);
FORCEADD TAP..1
R 2
(-7825 3475);
FORCEPROP 3 LASTPIN (-7775 3475) SIG_NAME M_F_CPU1_SB_CB<3>
J 0
(-7765 3485);
DISPLAY 0.659574 (-7765 3485);
PAINT MONO (-7765 3485);
DISPLAY INVISIBLE (-7765 3485);
FORCEPROP 1 LASTPIN (-7775 3475) BN 3
J 2
(-7763 3483);
DISPLAY 0.489362 (-7763 3483);
PAINT GREEN (-7763 3483);
FORCEPROP 2 LAST CDS_LIB mstr_standard
J 0
(-7825 3475);
DISPLAY 0.723404 (-7825 3475);
PAINT MONO (-7825 3475);
DISPLAY INVISIBLE (-7825 3475);
FORCEPROP 1 LAST BODY_TYPE PLUMBING
J 2
(-7825 3525);
DISPLAY 0.872340 (-7825 3525);
PAINT GREEN (-7825 3525);
DISPLAY INVISIBLE (-7825 3525);
FORCEPROP 1 LAST HDL_TAP TRUE
J 2
(-8150 3350);
DISPLAY 0.872340 (-8150 3350);
DISPLAY INVISIBLE (-8150 3350);
FORCEPROP 1 LAST PATH I26
J 2
(-7823 3475);
DISPLAY 0.872340 (-7823 3475);
PAINT GREEN (-7823 3475);
DISPLAY INVISIBLE (-7823 3475);
FORCEADD TAP..1
R 2
(-7825 3525);
FORCEPROP 3 LASTPIN (-7775 3525) SIG_NAME M_F_CPU1_SB_CB<4>
J 0
(-7765 3535);
DISPLAY 0.659574 (-7765 3535);
PAINT MONO (-7765 3535);
DISPLAY INVISIBLE (-7765 3535);
FORCEPROP 1 LASTPIN (-7775 3525) BN 4
J 2
(-7763 3533);
DISPLAY 0.489362 (-7763 3533);
PAINT GREEN (-7763 3533);
FORCEPROP 2 LAST CDS_LIB mstr_standard
J 0
(-7825 3525);
DISPLAY 0.723404 (-7825 3525);
PAINT MONO (-7825 3525);
DISPLAY INVISIBLE (-7825 3525);
FORCEPROP 1 LAST BODY_TYPE PLUMBING
J 2
(-7825 3575);
DISPLAY 0.872340 (-7825 3575);
PAINT GREEN (-7825 3575);
DISPLAY INVISIBLE (-7825 3575);
FORCEPROP 1 LAST HDL_TAP TRUE
J 2
(-8150 3400);
DISPLAY 0.872340 (-8150 3400);
DISPLAY INVISIBLE (-8150 3400);
FORCEPROP 1 LAST PATH I27
J 2
(-7823 3525);
DISPLAY 0.872340 (-7823 3525);
PAINT GREEN (-7823 3525);
DISPLAY INVISIBLE (-7823 3525);
FORCEADD TAP..1
R 2
(-7825 3625);
FORCEPROP 3 LASTPIN (-7775 3625) SIG_NAME M_F_CPU1_SB_CB<6>
J 0
(-7765 3635);
DISPLAY 0.659574 (-7765 3635);
PAINT MONO (-7765 3635);
DISPLAY INVISIBLE (-7765 3635);
FORCEPROP 1 LASTPIN (-7775 3625) BN 6
J 2
(-7763 3633);
DISPLAY 0.489362 (-7763 3633);
PAINT GREEN (-7763 3633);
FORCEPROP 2 LAST CDS_LIB mstr_standard
J 0
(-7825 3625);
DISPLAY 0.723404 (-7825 3625);
PAINT MONO (-7825 3625);
DISPLAY INVISIBLE (-7825 3625);
FORCEPROP 1 LAST BODY_TYPE PLUMBING
J 2
(-7825 3675);
DISPLAY 0.872340 (-7825 3675);
PAINT GREEN (-7825 3675);
DISPLAY INVISIBLE (-7825 3675);
FORCEPROP 1 LAST HDL_TAP TRUE
J 2
(-8150 3500);
DISPLAY 0.872340 (-8150 3500);
DISPLAY INVISIBLE (-8150 3500);
FORCEPROP 1 LAST PATH I28
J 2
(-7823 3625);
DISPLAY 0.872340 (-7823 3625);
PAINT GREEN (-7823 3625);
DISPLAY INVISIBLE (-7823 3625);
FORCEADD TAP..1
R 2
(-7825 3575);
FORCEPROP 3 LASTPIN (-7775 3575) SIG_NAME M_F_CPU1_SB_CB<5>
J 0
(-7765 3585);
DISPLAY 0.659574 (-7765 3585);
PAINT MONO (-7765 3585);
DISPLAY INVISIBLE (-7765 3585);
FORCEPROP 1 LASTPIN (-7775 3575) BN 5
J 2
(-7763 3583);
DISPLAY 0.489362 (-7763 3583);
PAINT GREEN (-7763 3583);
FORCEPROP 2 LAST CDS_LIB mstr_standard
J 0
(-7825 3575);
DISPLAY 0.723404 (-7825 3575);
PAINT MONO (-7825 3575);
DISPLAY INVISIBLE (-7825 3575);
FORCEPROP 1 LAST BODY_TYPE PLUMBING
J 2
(-7825 3625);
DISPLAY 0.872340 (-7825 3625);
PAINT GREEN (-7825 3625);
DISPLAY INVISIBLE (-7825 3625);
FORCEPROP 1 LAST HDL_TAP TRUE
J 2
(-8150 3450);
DISPLAY 0.872340 (-8150 3450);
DISPLAY INVISIBLE (-8150 3450);
FORCEPROP 1 LAST PATH I29
J 2
(-7823 3575);
DISPLAY 0.872340 (-7823 3575);
PAINT GREEN (-7823 3575);
DISPLAY INVISIBLE (-7823 3575);
FORCEADD TAP..1
R 2
(-7825 3675);
FORCEPROP 3 LASTPIN (-7775 3675) SIG_NAME M_F_CPU1_SB_CB<7>
J 0
(-7765 3685);
DISPLAY 0.659574 (-7765 3685);
PAINT MONO (-7765 3685);
DISPLAY INVISIBLE (-7765 3685);
FORCEPROP 1 LASTPIN (-7775 3675) BN 7
J 2
(-7763 3683);
DISPLAY 0.489362 (-7763 3683);
PAINT GREEN (-7763 3683);
FORCEPROP 2 LAST CDS_LIB mstr_standard
J 0
(-7825 3675);
DISPLAY 0.723404 (-7825 3675);
PAINT MONO (-7825 3675);
DISPLAY INVISIBLE (-7825 3675);
FORCEPROP 1 LAST BODY_TYPE PLUMBING
J 2
(-7825 3725);
DISPLAY 0.872340 (-7825 3725);
PAINT GREEN (-7825 3725);
DISPLAY INVISIBLE (-7825 3725);
FORCEPROP 1 LAST HDL_TAP TRUE
J 2
(-8150 3550);
DISPLAY 0.872340 (-8150 3550);
DISPLAY INVISIBLE (-8150 3550);
FORCEPROP 1 LAST PATH I30
J 2
(-7823 3675);
DISPLAY 0.872340 (-7823 3675);
PAINT GREEN (-7823 3675);
DISPLAY INVISIBLE (-7823 3675);
FORCEADD TAP..1
R 2
(-7825 3775);
FORCEPROP 3 LASTPIN (-7775 3775) SIG_NAME M_F_CPU1_SA_CB<0>
J 0
(-7765 3785);
DISPLAY 0.659574 (-7765 3785);
PAINT MONO (-7765 3785);
DISPLAY INVISIBLE (-7765 3785);
FORCEPROP 1 LASTPIN (-7775 3775) BN 0
J 2
(-7763 3783);
DISPLAY 0.489362 (-7763 3783);
PAINT GREEN (-7763 3783);
FORCEPROP 2 LAST CDS_LIB mstr_standard
J 0
(-7825 3775);
DISPLAY 0.723404 (-7825 3775);
PAINT MONO (-7825 3775);
DISPLAY INVISIBLE (-7825 3775);
FORCEPROP 1 LAST BODY_TYPE PLUMBING
J 2
(-7825 3825);
DISPLAY 0.872340 (-7825 3825);
PAINT GREEN (-7825 3825);
DISPLAY INVISIBLE (-7825 3825);
FORCEPROP 1 LAST HDL_TAP TRUE
J 2
(-8150 3650);
DISPLAY 0.872340 (-8150 3650);
DISPLAY INVISIBLE (-8150 3650);
FORCEPROP 1 LAST PATH I31
J 2
(-7823 3775);
DISPLAY 0.872340 (-7823 3775);
PAINT GREEN (-7823 3775);
DISPLAY INVISIBLE (-7823 3775);
FORCEADD TAP..1
R 2
(-7825 3825);
FORCEPROP 3 LASTPIN (-7775 3825) SIG_NAME M_F_CPU1_SA_CB<1>
J 0
(-7765 3835);
DISPLAY 0.659574 (-7765 3835);
PAINT MONO (-7765 3835);
DISPLAY INVISIBLE (-7765 3835);
FORCEPROP 1 LASTPIN (-7775 3825) BN 1
J 2
(-7763 3833);
DISPLAY 0.489362 (-7763 3833);
PAINT GREEN (-7763 3833);
FORCEPROP 2 LAST CDS_LIB mstr_standard
J 0
(-7825 3825);
DISPLAY 0.723404 (-7825 3825);
PAINT MONO (-7825 3825);
DISPLAY INVISIBLE (-7825 3825);
FORCEPROP 1 LAST BODY_TYPE PLUMBING
J 2
(-7825 3875);
DISPLAY 0.872340 (-7825 3875);
PAINT GREEN (-7825 3875);
DISPLAY INVISIBLE (-7825 3875);
FORCEPROP 1 LAST HDL_TAP TRUE
J 2
(-8150 3700);
DISPLAY 0.872340 (-8150 3700);
DISPLAY INVISIBLE (-8150 3700);
FORCEPROP 1 LAST PATH I32
J 2
(-7823 3825);
DISPLAY 0.872340 (-7823 3825);
PAINT GREEN (-7823 3825);
DISPLAY INVISIBLE (-7823 3825);
FORCEADD TAP..1
R 2
(-7825 3875);
FORCEPROP 3 LASTPIN (-7775 3875) SIG_NAME M_F_CPU1_SA_CB<2>
J 0
(-7765 3885);
DISPLAY 0.659574 (-7765 3885);
PAINT MONO (-7765 3885);
DISPLAY INVISIBLE (-7765 3885);
FORCEPROP 1 LASTPIN (-7775 3875) BN 2
J 2
(-7763 3883);
DISPLAY 0.489362 (-7763 3883);
PAINT GREEN (-7763 3883);
FORCEPROP 2 LAST CDS_LIB mstr_standard
J 0
(-7825 3875);
DISPLAY 0.723404 (-7825 3875);
PAINT MONO (-7825 3875);
DISPLAY INVISIBLE (-7825 3875);
FORCEPROP 1 LAST BODY_TYPE PLUMBING
J 2
(-7825 3925);
DISPLAY 0.872340 (-7825 3925);
PAINT GREEN (-7825 3925);
DISPLAY INVISIBLE (-7825 3925);
FORCEPROP 1 LAST HDL_TAP TRUE
J 2
(-8150 3750);
DISPLAY 0.872340 (-8150 3750);
DISPLAY INVISIBLE (-8150 3750);
FORCEPROP 1 LAST PATH I33
J 2
(-7823 3875);
DISPLAY 0.872340 (-7823 3875);
PAINT GREEN (-7823 3875);
DISPLAY INVISIBLE (-7823 3875);
FORCEADD TAP..1
R 2
(-7825 3925);
FORCEPROP 3 LASTPIN (-7775 3925) SIG_NAME M_F_CPU1_SA_CB<3>
J 0
(-7765 3935);
DISPLAY 0.659574 (-7765 3935);
PAINT MONO (-7765 3935);
DISPLAY INVISIBLE (-7765 3935);
FORCEPROP 1 LASTPIN (-7775 3925) BN 3
J 2
(-7763 3933);
DISPLAY 0.489362 (-7763 3933);
PAINT GREEN (-7763 3933);
FORCEPROP 2 LAST CDS_LIB mstr_standard
J 0
(-7825 3925);
DISPLAY 0.723404 (-7825 3925);
PAINT MONO (-7825 3925);
DISPLAY INVISIBLE (-7825 3925);
FORCEPROP 1 LAST BODY_TYPE PLUMBING
J 2
(-7825 3975);
DISPLAY 0.872340 (-7825 3975);
PAINT GREEN (-7825 3975);
DISPLAY INVISIBLE (-7825 3975);
FORCEPROP 1 LAST HDL_TAP TRUE
J 2
(-8150 3800);
DISPLAY 0.872340 (-8150 3800);
DISPLAY INVISIBLE (-8150 3800);
FORCEPROP 1 LAST PATH I34
J 2
(-7823 3925);
DISPLAY 0.872340 (-7823 3925);
PAINT GREEN (-7823 3925);
DISPLAY INVISIBLE (-7823 3925);
FORCEADD TAP..1
(-6125 2325);
FORCEPROP 3 LASTPIN (-6175 2325) SIG_NAME M_F_CPU1_SB_DQ<0>
J 0
(-6165 2335);
DISPLAY 0.659574 (-6165 2335);
PAINT MONO (-6165 2335);
DISPLAY INVISIBLE (-6165 2335);
FORCEPROP 1 LASTPIN (-6175 2325) BN 0
J 0
(-6187 2333);
DISPLAY 0.489362 (-6187 2333);
PAINT GREEN (-6187 2333);
FORCEPROP 2 LAST CDS_LIB mstr_standard
J 0
(-6125 2325);
DISPLAY 0.723404 (-6125 2325);
PAINT MONO (-6125 2325);
DISPLAY INVISIBLE (-6125 2325);
FORCEPROP 1 LAST BODY_TYPE PLUMBING
J 0
(-6125 2375);
DISPLAY 0.872340 (-6125 2375);
PAINT GREEN (-6125 2375);
DISPLAY INVISIBLE (-6125 2375);
FORCEPROP 1 LAST HDL_TAP TRUE
J 0
(-5800 2200);
DISPLAY 0.872340 (-5800 2200);
DISPLAY INVISIBLE (-5800 2200);
FORCEPROP 1 LAST PATH I35
J 0
(-6127 2325);
DISPLAY 0.872340 (-6127 2325);
PAINT GREEN (-6127 2325);
DISPLAY INVISIBLE (-6127 2325);
FORCEADD TAP..1
(-6125 2375);
FORCEPROP 3 LASTPIN (-6175 2375) SIG_NAME M_F_CPU1_SB_DQ<1>
J 0
(-6165 2385);
DISPLAY 0.659574 (-6165 2385);
PAINT MONO (-6165 2385);
DISPLAY INVISIBLE (-6165 2385);
FORCEPROP 1 LASTPIN (-6175 2375) BN 1
J 0
(-6187 2383);
DISPLAY 0.489362 (-6187 2383);
PAINT GREEN (-6187 2383);
FORCEPROP 2 LAST CDS_LIB mstr_standard
J 0
(-6125 2375);
DISPLAY 0.723404 (-6125 2375);
PAINT MONO (-6125 2375);
DISPLAY INVISIBLE (-6125 2375);
FORCEPROP 1 LAST BODY_TYPE PLUMBING
J 0
(-6125 2425);
DISPLAY 0.872340 (-6125 2425);
PAINT GREEN (-6125 2425);
DISPLAY INVISIBLE (-6125 2425);
FORCEPROP 1 LAST HDL_TAP TRUE
J 0
(-5800 2250);
DISPLAY 0.872340 (-5800 2250);
DISPLAY INVISIBLE (-5800 2250);
FORCEPROP 1 LAST PATH I36
J 0
(-6127 2375);
DISPLAY 0.872340 (-6127 2375);
PAINT GREEN (-6127 2375);
DISPLAY INVISIBLE (-6127 2375);
FORCEADD TAP..1
(-6125 2425);
FORCEPROP 3 LASTPIN (-6175 2425) SIG_NAME M_F_CPU1_SB_DQ<2>
J 0
(-6165 2435);
DISPLAY 0.659574 (-6165 2435);
PAINT MONO (-6165 2435);
DISPLAY INVISIBLE (-6165 2435);
FORCEPROP 1 LASTPIN (-6175 2425) BN 2
J 0
(-6187 2433);
DISPLAY 0.489362 (-6187 2433);
PAINT GREEN (-6187 2433);
FORCEPROP 2 LAST CDS_LIB mstr_standard
J 0
(-6125 2425);
DISPLAY 0.723404 (-6125 2425);
PAINT MONO (-6125 2425);
DISPLAY INVISIBLE (-6125 2425);
FORCEPROP 1 LAST BODY_TYPE PLUMBING
J 0
(-6125 2475);
DISPLAY 0.872340 (-6125 2475);
PAINT GREEN (-6125 2475);
DISPLAY INVISIBLE (-6125 2475);
FORCEPROP 1 LAST HDL_TAP TRUE
J 0
(-5800 2300);
DISPLAY 0.872340 (-5800 2300);
DISPLAY INVISIBLE (-5800 2300);
FORCEPROP 1 LAST PATH I37
J 0
(-6127 2425);
DISPLAY 0.872340 (-6127 2425);
PAINT GREEN (-6127 2425);
DISPLAY INVISIBLE (-6127 2425);
FORCEADD TAP..1
(-6125 2475);
FORCEPROP 3 LASTPIN (-6175 2475) SIG_NAME M_F_CPU1_SB_DQ<3>
J 0
(-6165 2485);
DISPLAY 0.659574 (-6165 2485);
PAINT MONO (-6165 2485);
DISPLAY INVISIBLE (-6165 2485);
FORCEPROP 1 LASTPIN (-6175 2475) BN 3
J 0
(-6187 2483);
DISPLAY 0.489362 (-6187 2483);
PAINT GREEN (-6187 2483);
FORCEPROP 2 LAST CDS_LIB mstr_standard
J 0
(-6125 2475);
DISPLAY 0.723404 (-6125 2475);
PAINT MONO (-6125 2475);
DISPLAY INVISIBLE (-6125 2475);
FORCEPROP 1 LAST BODY_TYPE PLUMBING
J 0
(-6125 2525);
DISPLAY 0.872340 (-6125 2525);
PAINT GREEN (-6125 2525);
DISPLAY INVISIBLE (-6125 2525);
FORCEPROP 1 LAST HDL_TAP TRUE
J 0
(-5800 2350);
DISPLAY 0.872340 (-5800 2350);
DISPLAY INVISIBLE (-5800 2350);
FORCEPROP 1 LAST PATH I38
J 0
(-6127 2475);
DISPLAY 0.872340 (-6127 2475);
PAINT GREEN (-6127 2475);
DISPLAY INVISIBLE (-6127 2475);
FORCEADD TAP..1
(-6125 2525);
FORCEPROP 3 LASTPIN (-6175 2525) SIG_NAME M_F_CPU1_SB_DQ<4>
J 0
(-6165 2535);
DISPLAY 0.659574 (-6165 2535);
PAINT MONO (-6165 2535);
DISPLAY INVISIBLE (-6165 2535);
FORCEPROP 1 LASTPIN (-6175 2525) BN 4
J 0
(-6187 2533);
DISPLAY 0.489362 (-6187 2533);
PAINT GREEN (-6187 2533);
FORCEPROP 2 LAST CDS_LIB mstr_standard
J 0
(-6125 2525);
DISPLAY 0.723404 (-6125 2525);
PAINT MONO (-6125 2525);
DISPLAY INVISIBLE (-6125 2525);
FORCEPROP 1 LAST BODY_TYPE PLUMBING
J 0
(-6125 2575);
DISPLAY 0.872340 (-6125 2575);
PAINT GREEN (-6125 2575);
DISPLAY INVISIBLE (-6125 2575);
FORCEPROP 1 LAST HDL_TAP TRUE
J 0
(-5800 2400);
DISPLAY 0.872340 (-5800 2400);
DISPLAY INVISIBLE (-5800 2400);
FORCEPROP 1 LAST PATH I39
J 0
(-6127 2525);
DISPLAY 0.872340 (-6127 2525);
PAINT GREEN (-6127 2525);
DISPLAY INVISIBLE (-6127 2525);
FORCEADD TAP..1
(-6125 2575);
FORCEPROP 3 LASTPIN (-6175 2575) SIG_NAME M_F_CPU1_SB_DQ<5>
J 0
(-6165 2585);
DISPLAY 0.659574 (-6165 2585);
PAINT MONO (-6165 2585);
DISPLAY INVISIBLE (-6165 2585);
FORCEPROP 1 LASTPIN (-6175 2575) BN 5
J 0
(-6187 2583);
DISPLAY 0.489362 (-6187 2583);
PAINT GREEN (-6187 2583);
FORCEPROP 2 LAST CDS_LIB mstr_standard
J 0
(-6125 2575);
DISPLAY 0.723404 (-6125 2575);
PAINT MONO (-6125 2575);
DISPLAY INVISIBLE (-6125 2575);
FORCEPROP 1 LAST BODY_TYPE PLUMBING
J 0
(-6125 2625);
DISPLAY 0.872340 (-6125 2625);
PAINT GREEN (-6125 2625);
DISPLAY INVISIBLE (-6125 2625);
FORCEPROP 1 LAST HDL_TAP TRUE
J 0
(-5800 2450);
DISPLAY 0.872340 (-5800 2450);
DISPLAY INVISIBLE (-5800 2450);
FORCEPROP 1 LAST PATH I40
J 0
(-6127 2575);
DISPLAY 0.872340 (-6127 2575);
PAINT GREEN (-6127 2575);
DISPLAY INVISIBLE (-6127 2575);
FORCEADD TAP..1
(-6125 2625);
FORCEPROP 3 LASTPIN (-6175 2625) SIG_NAME M_F_CPU1_SB_DQ<6>
J 0
(-6165 2635);
DISPLAY 0.659574 (-6165 2635);
PAINT MONO (-6165 2635);
DISPLAY INVISIBLE (-6165 2635);
FORCEPROP 1 LASTPIN (-6175 2625) BN 6
J 0
(-6187 2633);
DISPLAY 0.489362 (-6187 2633);
PAINT GREEN (-6187 2633);
FORCEPROP 2 LAST CDS_LIB mstr_standard
J 0
(-6125 2625);
DISPLAY 0.723404 (-6125 2625);
PAINT MONO (-6125 2625);
DISPLAY INVISIBLE (-6125 2625);
FORCEPROP 1 LAST BODY_TYPE PLUMBING
J 0
(-6125 2675);
DISPLAY 0.872340 (-6125 2675);
PAINT GREEN (-6125 2675);
DISPLAY INVISIBLE (-6125 2675);
FORCEPROP 1 LAST HDL_TAP TRUE
J 0
(-5800 2500);
DISPLAY 0.872340 (-5800 2500);
DISPLAY INVISIBLE (-5800 2500);
FORCEPROP 1 LAST PATH I41
J 0
(-6127 2625);
DISPLAY 0.872340 (-6127 2625);
PAINT GREEN (-6127 2625);
DISPLAY INVISIBLE (-6127 2625);
FORCEADD TAP..1
(-6125 2675);
FORCEPROP 3 LASTPIN (-6175 2675) SIG_NAME M_F_CPU1_SB_DQ<7>
J 0
(-6165 2685);
DISPLAY 0.659574 (-6165 2685);
PAINT MONO (-6165 2685);
DISPLAY INVISIBLE (-6165 2685);
FORCEPROP 1 LASTPIN (-6175 2675) BN 7
J 0
(-6187 2683);
DISPLAY 0.489362 (-6187 2683);
PAINT GREEN (-6187 2683);
FORCEPROP 2 LAST CDS_LIB mstr_standard
J 0
(-6125 2675);
DISPLAY 0.723404 (-6125 2675);
PAINT MONO (-6125 2675);
DISPLAY INVISIBLE (-6125 2675);
FORCEPROP 1 LAST BODY_TYPE PLUMBING
J 0
(-6125 2725);
DISPLAY 0.872340 (-6125 2725);
PAINT GREEN (-6125 2725);
DISPLAY INVISIBLE (-6125 2725);
FORCEPROP 1 LAST HDL_TAP TRUE
J 0
(-5800 2550);
DISPLAY 0.872340 (-5800 2550);
DISPLAY INVISIBLE (-5800 2550);
FORCEPROP 1 LAST PATH I42
J 0
(-6127 2675);
DISPLAY 0.872340 (-6127 2675);
PAINT GREEN (-6127 2675);
DISPLAY INVISIBLE (-6127 2675);
FORCEADD TAP..1
(-6125 2725);
FORCEPROP 3 LASTPIN (-6175 2725) SIG_NAME M_F_CPU1_SB_DQ<8>
J 0
(-6165 2735);
DISPLAY 0.659574 (-6165 2735);
PAINT MONO (-6165 2735);
DISPLAY INVISIBLE (-6165 2735);
FORCEPROP 1 LASTPIN (-6175 2725) BN 8
J 0
(-6187 2733);
DISPLAY 0.489362 (-6187 2733);
PAINT GREEN (-6187 2733);
FORCEPROP 2 LAST CDS_LIB mstr_standard
J 0
(-6125 2725);
DISPLAY 0.723404 (-6125 2725);
PAINT MONO (-6125 2725);
DISPLAY INVISIBLE (-6125 2725);
FORCEPROP 1 LAST BODY_TYPE PLUMBING
J 0
(-6125 2775);
DISPLAY 0.872340 (-6125 2775);
PAINT GREEN (-6125 2775);
DISPLAY INVISIBLE (-6125 2775);
FORCEPROP 1 LAST HDL_TAP TRUE
J 0
(-5800 2600);
DISPLAY 0.872340 (-5800 2600);
DISPLAY INVISIBLE (-5800 2600);
FORCEPROP 1 LAST PATH I43
J 0
(-6127 2725);
DISPLAY 0.872340 (-6127 2725);
PAINT GREEN (-6127 2725);
DISPLAY INVISIBLE (-6127 2725);
FORCEADD TAP..1
(-6125 2775);
FORCEPROP 3 LASTPIN (-6175 2775) SIG_NAME M_F_CPU1_SB_DQ<9>
J 0
(-6165 2785);
DISPLAY 0.659574 (-6165 2785);
PAINT MONO (-6165 2785);
DISPLAY INVISIBLE (-6165 2785);
FORCEPROP 1 LASTPIN (-6175 2775) BN 9
J 0
(-6187 2783);
DISPLAY 0.489362 (-6187 2783);
PAINT GREEN (-6187 2783);
FORCEPROP 2 LAST CDS_LIB mstr_standard
J 0
(-6125 2775);
DISPLAY 0.723404 (-6125 2775);
PAINT MONO (-6125 2775);
DISPLAY INVISIBLE (-6125 2775);
FORCEPROP 1 LAST BODY_TYPE PLUMBING
J 0
(-6125 2825);
DISPLAY 0.872340 (-6125 2825);
PAINT GREEN (-6125 2825);
DISPLAY INVISIBLE (-6125 2825);
FORCEPROP 1 LAST HDL_TAP TRUE
J 0
(-5800 2650);
DISPLAY 0.872340 (-5800 2650);
DISPLAY INVISIBLE (-5800 2650);
FORCEPROP 1 LAST PATH I44
J 0
(-6127 2775);
DISPLAY 0.872340 (-6127 2775);
PAINT GREEN (-6127 2775);
DISPLAY INVISIBLE (-6127 2775);
FORCEADD TAP..1
(-6125 2825);
FORCEPROP 3 LASTPIN (-6175 2825) SIG_NAME M_F_CPU1_SB_DQ<10>
J 0
(-6165 2835);
DISPLAY 0.659574 (-6165 2835);
PAINT MONO (-6165 2835);
DISPLAY INVISIBLE (-6165 2835);
FORCEPROP 1 LASTPIN (-6175 2825) BN 10
J 0
(-6187 2833);
DISPLAY 0.489362 (-6187 2833);
PAINT GREEN (-6187 2833);
FORCEPROP 2 LAST CDS_LIB mstr_standard
J 0
(-6125 2825);
DISPLAY 0.723404 (-6125 2825);
PAINT MONO (-6125 2825);
DISPLAY INVISIBLE (-6125 2825);
FORCEPROP 1 LAST BODY_TYPE PLUMBING
J 0
(-6125 2875);
DISPLAY 0.872340 (-6125 2875);
PAINT GREEN (-6125 2875);
DISPLAY INVISIBLE (-6125 2875);
FORCEPROP 1 LAST HDL_TAP TRUE
J 0
(-5800 2700);
DISPLAY 0.872340 (-5800 2700);
DISPLAY INVISIBLE (-5800 2700);
FORCEPROP 1 LAST PATH I45
J 0
(-6127 2825);
DISPLAY 0.872340 (-6127 2825);
PAINT GREEN (-6127 2825);
DISPLAY INVISIBLE (-6127 2825);
FORCEADD TAP..1
(-6125 2875);
FORCEPROP 3 LASTPIN (-6175 2875) SIG_NAME M_F_CPU1_SB_DQ<11>
J 0
(-6165 2885);
DISPLAY 0.659574 (-6165 2885);
PAINT MONO (-6165 2885);
DISPLAY INVISIBLE (-6165 2885);
FORCEPROP 1 LASTPIN (-6175 2875) BN 11
J 0
(-6187 2883);
DISPLAY 0.489362 (-6187 2883);
PAINT GREEN (-6187 2883);
FORCEPROP 2 LAST CDS_LIB mstr_standard
J 0
(-6125 2875);
DISPLAY 0.723404 (-6125 2875);
PAINT MONO (-6125 2875);
DISPLAY INVISIBLE (-6125 2875);
FORCEPROP 1 LAST BODY_TYPE PLUMBING
J 0
(-6125 2925);
DISPLAY 0.872340 (-6125 2925);
PAINT GREEN (-6125 2925);
DISPLAY INVISIBLE (-6125 2925);
FORCEPROP 1 LAST HDL_TAP TRUE
J 0
(-5800 2750);
DISPLAY 0.872340 (-5800 2750);
DISPLAY INVISIBLE (-5800 2750);
FORCEPROP 1 LAST PATH I46
J 0
(-6127 2875);
DISPLAY 0.872340 (-6127 2875);
PAINT GREEN (-6127 2875);
DISPLAY INVISIBLE (-6127 2875);
FORCEADD TAP..1
(-6125 2925);
FORCEPROP 3 LASTPIN (-6175 2925) SIG_NAME M_F_CPU1_SB_DQ<12>
J 0
(-6165 2935);
DISPLAY 0.659574 (-6165 2935);
PAINT MONO (-6165 2935);
DISPLAY INVISIBLE (-6165 2935);
FORCEPROP 1 LASTPIN (-6175 2925) BN 12
J 0
(-6187 2933);
DISPLAY 0.489362 (-6187 2933);
PAINT GREEN (-6187 2933);
FORCEPROP 2 LAST CDS_LIB mstr_standard
J 0
(-6125 2925);
DISPLAY 0.723404 (-6125 2925);
PAINT MONO (-6125 2925);
DISPLAY INVISIBLE (-6125 2925);
FORCEPROP 1 LAST BODY_TYPE PLUMBING
J 0
(-6125 2975);
DISPLAY 0.872340 (-6125 2975);
PAINT GREEN (-6125 2975);
DISPLAY INVISIBLE (-6125 2975);
FORCEPROP 1 LAST HDL_TAP TRUE
J 0
(-5800 2800);
DISPLAY 0.872340 (-5800 2800);
DISPLAY INVISIBLE (-5800 2800);
FORCEPROP 1 LAST PATH I47
J 0
(-6127 2925);
DISPLAY 0.872340 (-6127 2925);
PAINT GREEN (-6127 2925);
DISPLAY INVISIBLE (-6127 2925);
FORCEADD TAP..1
(-6125 2975);
FORCEPROP 3 LASTPIN (-6175 2975) SIG_NAME M_F_CPU1_SB_DQ<13>
J 0
(-6165 2985);
DISPLAY 0.659574 (-6165 2985);
PAINT MONO (-6165 2985);
DISPLAY INVISIBLE (-6165 2985);
FORCEPROP 1 LASTPIN (-6175 2975) BN 13
J 0
(-6187 2983);
DISPLAY 0.489362 (-6187 2983);
PAINT GREEN (-6187 2983);
FORCEPROP 2 LAST CDS_LIB mstr_standard
J 0
(-6125 2975);
DISPLAY 0.723404 (-6125 2975);
PAINT MONO (-6125 2975);
DISPLAY INVISIBLE (-6125 2975);
FORCEPROP 1 LAST BODY_TYPE PLUMBING
J 0
(-6125 3025);
DISPLAY 0.872340 (-6125 3025);
PAINT GREEN (-6125 3025);
DISPLAY INVISIBLE (-6125 3025);
FORCEPROP 1 LAST HDL_TAP TRUE
J 0
(-5800 2850);
DISPLAY 0.872340 (-5800 2850);
DISPLAY INVISIBLE (-5800 2850);
FORCEPROP 1 LAST PATH I48
J 0
(-6127 2975);
DISPLAY 0.872340 (-6127 2975);
PAINT GREEN (-6127 2975);
DISPLAY INVISIBLE (-6127 2975);
FORCEADD TAP..1
(-6125 3025);
FORCEPROP 3 LASTPIN (-6175 3025) SIG_NAME M_F_CPU1_SB_DQ<14>
J 0
(-6165 3035);
DISPLAY 0.659574 (-6165 3035);
PAINT MONO (-6165 3035);
DISPLAY INVISIBLE (-6165 3035);
FORCEPROP 1 LASTPIN (-6175 3025) BN 14
J 0
(-6187 3033);
DISPLAY 0.489362 (-6187 3033);
PAINT GREEN (-6187 3033);
FORCEPROP 2 LAST CDS_LIB mstr_standard
J 0
(-6125 3025);
DISPLAY 0.723404 (-6125 3025);
PAINT MONO (-6125 3025);
DISPLAY INVISIBLE (-6125 3025);
FORCEPROP 1 LAST BODY_TYPE PLUMBING
J 0
(-6125 3075);
DISPLAY 0.872340 (-6125 3075);
PAINT GREEN (-6125 3075);
DISPLAY INVISIBLE (-6125 3075);
FORCEPROP 1 LAST HDL_TAP TRUE
J 0
(-5800 2900);
DISPLAY 0.872340 (-5800 2900);
DISPLAY INVISIBLE (-5800 2900);
FORCEPROP 1 LAST PATH I49
J 0
(-6127 3025);
DISPLAY 0.872340 (-6127 3025);
PAINT GREEN (-6127 3025);
DISPLAY INVISIBLE (-6127 3025);
FORCEADD VCC_CORE..1
(-8575 3550);
FORCEPROP 3 LASTPIN (-8575 3500) SIG_NAME P3V3_AUX\g
J 0
(-8565 3510);
DISPLAY 0.659574 (-8565 3510);
PAINT MONO (-8565 3510);
DISPLAY INVISIBLE (-8565 3510);
FORCEPROP 1 LAST HDL_POWER P3V3_AUX
J 1
(-8575 3600);
DISPLAY 0.489362 (-8575 3600);
PAINT GREEN (-8575 3600);
FORCEPROP 2 LAST CDS_LIB mstr_symbols
J 0
(-8575 3550);
PAINT MONO (-8575 3550);
DISPLAY INVISIBLE (-8575 3550);
FORCEPROP 0 LAST VOLTAGE 3.3
J 0
(-8850 3700);
DISPLAY 1.021277 (-8850 3700);
PAINT SKYBLUE (-8850 3700);
DISPLAY INVISIBLE (-8850 3700);
FORCEPROP 2 LAST ROOM PVCCINFAON_CPU1_CTRL
J 0
(-8575 3650);
DISPLAY 0.808511 (-8575 3650);
PAINT RED (-8575 3650);
DISPLAY INVISIBLE (-8575 3650);
FORCEPROP 1 LAST PATH I5
J 0
(-8525 3575);
DISPLAY 0.872340 (-8525 3575);
PAINT AQUA (-8525 3575);
DISPLAY INVISIBLE (-8525 3575);
FORCEADD TAP..1
(-6125 3125);
FORCEPROP 3 LASTPIN (-6175 3125) SIG_NAME M_F_CPU1_SB_DQ<16>
J 0
(-6165 3135);
DISPLAY 0.659574 (-6165 3135);
PAINT MONO (-6165 3135);
DISPLAY INVISIBLE (-6165 3135);
FORCEPROP 1 LASTPIN (-6175 3125) BN 16
J 0
(-6187 3133);
DISPLAY 0.489362 (-6187 3133);
PAINT GREEN (-6187 3133);
FORCEPROP 2 LAST CDS_LIB mstr_standard
J 0
(-6125 3125);
DISPLAY 0.723404 (-6125 3125);
PAINT MONO (-6125 3125);
DISPLAY INVISIBLE (-6125 3125);
FORCEPROP 1 LAST BODY_TYPE PLUMBING
J 0
(-6125 3175);
DISPLAY 0.872340 (-6125 3175);
PAINT GREEN (-6125 3175);
DISPLAY INVISIBLE (-6125 3175);
FORCEPROP 1 LAST HDL_TAP TRUE
J 0
(-5800 3000);
DISPLAY 0.872340 (-5800 3000);
DISPLAY INVISIBLE (-5800 3000);
FORCEPROP 1 LAST PATH I50
J 0
(-6127 3125);
DISPLAY 0.872340 (-6127 3125);
PAINT GREEN (-6127 3125);
DISPLAY INVISIBLE (-6127 3125);
FORCEADD TAP..1
(-6125 3075);
FORCEPROP 3 LASTPIN (-6175 3075) SIG_NAME M_F_CPU1_SB_DQ<15>
J 0
(-6165 3085);
DISPLAY 0.659574 (-6165 3085);
PAINT MONO (-6165 3085);
DISPLAY INVISIBLE (-6165 3085);
FORCEPROP 1 LASTPIN (-6175 3075) BN 15
J 0
(-6187 3083);
DISPLAY 0.489362 (-6187 3083);
PAINT GREEN (-6187 3083);
FORCEPROP 2 LAST CDS_LIB mstr_standard
J 0
(-6125 3075);
DISPLAY 0.723404 (-6125 3075);
PAINT MONO (-6125 3075);
DISPLAY INVISIBLE (-6125 3075);
FORCEPROP 1 LAST BODY_TYPE PLUMBING
J 0
(-6125 3125);
DISPLAY 0.872340 (-6125 3125);
PAINT GREEN (-6125 3125);
DISPLAY INVISIBLE (-6125 3125);
FORCEPROP 1 LAST HDL_TAP TRUE
J 0
(-5800 2950);
DISPLAY 0.872340 (-5800 2950);
DISPLAY INVISIBLE (-5800 2950);
FORCEPROP 1 LAST PATH I51
J 0
(-6127 3075);
DISPLAY 0.872340 (-6127 3075);
PAINT GREEN (-6127 3075);
DISPLAY INVISIBLE (-6127 3075);
FORCEADD TAP..1
(-6125 3175);
FORCEPROP 3 LASTPIN (-6175 3175) SIG_NAME M_F_CPU1_SB_DQ<17>
J 0
(-6165 3185);
DISPLAY 0.659574 (-6165 3185);
PAINT MONO (-6165 3185);
DISPLAY INVISIBLE (-6165 3185);
FORCEPROP 1 LASTPIN (-6175 3175) BN 17
J 0
(-6187 3183);
DISPLAY 0.489362 (-6187 3183);
PAINT GREEN (-6187 3183);
FORCEPROP 2 LAST CDS_LIB mstr_standard
J 0
(-6125 3175);
DISPLAY 0.723404 (-6125 3175);
PAINT MONO (-6125 3175);
DISPLAY INVISIBLE (-6125 3175);
FORCEPROP 1 LAST BODY_TYPE PLUMBING
J 0
(-6125 3225);
DISPLAY 0.872340 (-6125 3225);
PAINT GREEN (-6125 3225);
DISPLAY INVISIBLE (-6125 3225);
FORCEPROP 1 LAST HDL_TAP TRUE
J 0
(-5800 3050);
DISPLAY 0.872340 (-5800 3050);
DISPLAY INVISIBLE (-5800 3050);
FORCEPROP 1 LAST PATH I52
J 0
(-6127 3175);
DISPLAY 0.872340 (-6127 3175);
PAINT GREEN (-6127 3175);
DISPLAY INVISIBLE (-6127 3175);
FORCEADD TAP..1
(-6125 3275);
FORCEPROP 3 LASTPIN (-6175 3275) SIG_NAME M_F_CPU1_SB_DQ<19>
J 0
(-6165 3285);
DISPLAY 0.659574 (-6165 3285);
PAINT MONO (-6165 3285);
DISPLAY INVISIBLE (-6165 3285);
FORCEPROP 1 LASTPIN (-6175 3275) BN 19
J 0
(-6187 3283);
DISPLAY 0.489362 (-6187 3283);
PAINT GREEN (-6187 3283);
FORCEPROP 2 LAST CDS_LIB mstr_standard
J 0
(-6125 3275);
DISPLAY 0.723404 (-6125 3275);
PAINT MONO (-6125 3275);
DISPLAY INVISIBLE (-6125 3275);
FORCEPROP 1 LAST BODY_TYPE PLUMBING
J 0
(-6125 3325);
DISPLAY 0.872340 (-6125 3325);
PAINT GREEN (-6125 3325);
DISPLAY INVISIBLE (-6125 3325);
FORCEPROP 1 LAST HDL_TAP TRUE
J 0
(-5800 3150);
DISPLAY 0.872340 (-5800 3150);
DISPLAY INVISIBLE (-5800 3150);
FORCEPROP 1 LAST PATH I53
J 0
(-6127 3275);
DISPLAY 0.872340 (-6127 3275);
PAINT GREEN (-6127 3275);
DISPLAY INVISIBLE (-6127 3275);
FORCEADD TAP..1
(-6125 3325);
FORCEPROP 3 LASTPIN (-6175 3325) SIG_NAME M_F_CPU1_SB_DQ<20>
J 0
(-6165 3335);
DISPLAY 0.659574 (-6165 3335);
PAINT MONO (-6165 3335);
DISPLAY INVISIBLE (-6165 3335);
FORCEPROP 1 LASTPIN (-6175 3325) BN 20
J 0
(-6187 3333);
DISPLAY 0.489362 (-6187 3333);
PAINT GREEN (-6187 3333);
FORCEPROP 2 LAST CDS_LIB mstr_standard
J 0
(-6125 3325);
DISPLAY 0.723404 (-6125 3325);
PAINT MONO (-6125 3325);
DISPLAY INVISIBLE (-6125 3325);
FORCEPROP 1 LAST BODY_TYPE PLUMBING
J 0
(-6125 3375);
DISPLAY 0.872340 (-6125 3375);
PAINT GREEN (-6125 3375);
DISPLAY INVISIBLE (-6125 3375);
FORCEPROP 1 LAST HDL_TAP TRUE
J 0
(-5800 3200);
DISPLAY 0.872340 (-5800 3200);
DISPLAY INVISIBLE (-5800 3200);
FORCEPROP 1 LAST PATH I54
J 0
(-6127 3325);
DISPLAY 0.872340 (-6127 3325);
PAINT GREEN (-6127 3325);
DISPLAY INVISIBLE (-6127 3325);
FORCEADD TAP..1
(-6125 3425);
FORCEPROP 3 LASTPIN (-6175 3425) SIG_NAME M_F_CPU1_SB_DQ<22>
J 0
(-6165 3435);
DISPLAY 0.659574 (-6165 3435);
PAINT MONO (-6165 3435);
DISPLAY INVISIBLE (-6165 3435);
FORCEPROP 1 LASTPIN (-6175 3425) BN 22
J 0
(-6187 3433);
DISPLAY 0.489362 (-6187 3433);
PAINT GREEN (-6187 3433);
FORCEPROP 2 LAST CDS_LIB mstr_standard
J 0
(-6125 3425);
DISPLAY 0.723404 (-6125 3425);
PAINT MONO (-6125 3425);
DISPLAY INVISIBLE (-6125 3425);
FORCEPROP 1 LAST BODY_TYPE PLUMBING
J 0
(-6125 3475);
DISPLAY 0.872340 (-6125 3475);
PAINT GREEN (-6125 3475);
DISPLAY INVISIBLE (-6125 3475);
FORCEPROP 1 LAST HDL_TAP TRUE
J 0
(-5800 3300);
DISPLAY 0.872340 (-5800 3300);
DISPLAY INVISIBLE (-5800 3300);
FORCEPROP 1 LAST PATH I55
J 0
(-6127 3425);
DISPLAY 0.872340 (-6127 3425);
PAINT GREEN (-6127 3425);
DISPLAY INVISIBLE (-6127 3425);
FORCEADD TAP..1
(-6125 3375);
FORCEPROP 3 LASTPIN (-6175 3375) SIG_NAME M_F_CPU1_SB_DQ<21>
J 0
(-6165 3385);
DISPLAY 0.659574 (-6165 3385);
PAINT MONO (-6165 3385);
DISPLAY INVISIBLE (-6165 3385);
FORCEPROP 1 LASTPIN (-6175 3375) BN 21
J 0
(-6187 3383);
DISPLAY 0.489362 (-6187 3383);
PAINT GREEN (-6187 3383);
FORCEPROP 2 LAST CDS_LIB mstr_standard
J 0
(-6125 3375);
DISPLAY 0.723404 (-6125 3375);
PAINT MONO (-6125 3375);
DISPLAY INVISIBLE (-6125 3375);
FORCEPROP 1 LAST BODY_TYPE PLUMBING
J 0
(-6125 3425);
DISPLAY 0.872340 (-6125 3425);
PAINT GREEN (-6125 3425);
DISPLAY INVISIBLE (-6125 3425);
FORCEPROP 1 LAST HDL_TAP TRUE
J 0
(-5800 3250);
DISPLAY 0.872340 (-5800 3250);
DISPLAY INVISIBLE (-5800 3250);
FORCEPROP 1 LAST PATH I56
J 0
(-6127 3375);
DISPLAY 0.872340 (-6127 3375);
PAINT GREEN (-6127 3375);
DISPLAY INVISIBLE (-6127 3375);
FORCEADD TAP..1
(-6125 3225);
FORCEPROP 3 LASTPIN (-6175 3225) SIG_NAME M_F_CPU1_SB_DQ<18>
J 0
(-6165 3235);
DISPLAY 0.659574 (-6165 3235);
PAINT MONO (-6165 3235);
DISPLAY INVISIBLE (-6165 3235);
FORCEPROP 1 LASTPIN (-6175 3225) BN 18
J 0
(-6187 3233);
DISPLAY 0.489362 (-6187 3233);
PAINT GREEN (-6187 3233);
FORCEPROP 2 LAST CDS_LIB mstr_standard
J 0
(-6125 3225);
DISPLAY 0.723404 (-6125 3225);
PAINT MONO (-6125 3225);
DISPLAY INVISIBLE (-6125 3225);
FORCEPROP 1 LAST BODY_TYPE PLUMBING
J 0
(-6125 3275);
DISPLAY 0.872340 (-6125 3275);
PAINT GREEN (-6125 3275);
DISPLAY INVISIBLE (-6125 3275);
FORCEPROP 1 LAST HDL_TAP TRUE
J 0
(-5800 3100);
DISPLAY 0.872340 (-5800 3100);
DISPLAY INVISIBLE (-5800 3100);
FORCEPROP 1 LAST PATH I57
J 0
(-6127 3225);
DISPLAY 0.872340 (-6127 3225);
PAINT GREEN (-6127 3225);
DISPLAY INVISIBLE (-6127 3225);
FORCEADD TAP..1
(-6125 3525);
FORCEPROP 3 LASTPIN (-6175 3525) SIG_NAME M_F_CPU1_SB_DQ<24>
J 0
(-6165 3535);
DISPLAY 0.659574 (-6165 3535);
PAINT MONO (-6165 3535);
DISPLAY INVISIBLE (-6165 3535);
FORCEPROP 1 LASTPIN (-6175 3525) BN 24
J 0
(-6187 3533);
DISPLAY 0.489362 (-6187 3533);
PAINT GREEN (-6187 3533);
FORCEPROP 2 LAST CDS_LIB mstr_standard
J 0
(-6125 3525);
DISPLAY 0.723404 (-6125 3525);
PAINT MONO (-6125 3525);
DISPLAY INVISIBLE (-6125 3525);
FORCEPROP 1 LAST BODY_TYPE PLUMBING
J 0
(-6125 3575);
DISPLAY 0.872340 (-6125 3575);
PAINT GREEN (-6125 3575);
DISPLAY INVISIBLE (-6125 3575);
FORCEPROP 1 LAST HDL_TAP TRUE
J 0
(-5800 3400);
DISPLAY 0.872340 (-5800 3400);
DISPLAY INVISIBLE (-5800 3400);
FORCEPROP 1 LAST PATH I58
J 0
(-6127 3525);
DISPLAY 0.872340 (-6127 3525);
PAINT GREEN (-6127 3525);
DISPLAY INVISIBLE (-6127 3525);
FORCEADD TAP..1
(-6125 3575);
FORCEPROP 3 LASTPIN (-6175 3575) SIG_NAME M_F_CPU1_SB_DQ<25>
J 0
(-6165 3585);
DISPLAY 0.659574 (-6165 3585);
PAINT MONO (-6165 3585);
DISPLAY INVISIBLE (-6165 3585);
FORCEPROP 1 LASTPIN (-6175 3575) BN 25
J 0
(-6187 3583);
DISPLAY 0.489362 (-6187 3583);
PAINT GREEN (-6187 3583);
FORCEPROP 2 LAST CDS_LIB mstr_standard
J 0
(-6125 3575);
DISPLAY 0.723404 (-6125 3575);
PAINT MONO (-6125 3575);
DISPLAY INVISIBLE (-6125 3575);
FORCEPROP 1 LAST BODY_TYPE PLUMBING
J 0
(-6125 3625);
DISPLAY 0.872340 (-6125 3625);
PAINT GREEN (-6125 3625);
DISPLAY INVISIBLE (-6125 3625);
FORCEPROP 1 LAST HDL_TAP TRUE
J 0
(-5800 3450);
DISPLAY 0.872340 (-5800 3450);
DISPLAY INVISIBLE (-5800 3450);
FORCEPROP 1 LAST PATH I59
J 0
(-6127 3575);
DISPLAY 0.872340 (-6127 3575);
PAINT GREEN (-6127 3575);
DISPLAY INVISIBLE (-6127 3575);
FORCEADD OFFPAGE..5
(-8225 3175);
FORCEPROP 2 LAST $XR0 42 
J 0
(-8449 3175);
DISPLAY 0.638298 (-8449 3175);
PAINT MONO (-8449 3175);
FORCEPROP 2 LAST CDS_LIB mstr_standard
J 0
(-8225 3175);
DISPLAY INVISIBLE (-8225 3175);
FORCEPROP 1 LAST OFFPAGE TRUE
J 0
(-7900 3050);
DISPLAY 0.872340 (-7900 3050);
PAINT GREEN (-7900 3050);
DISPLAY INVISIBLE (-7900 3050);
FORCEPROP 1 LAST COMMENT_BODY TRUE
J 0
(-8125 3100);
DISPLAY 0.872340 (-8125 3100);
PAINT GREEN (-8125 3100);
DISPLAY INVISIBLE (-8125 3100);
FORCEPROP 2 LAST PATH I6
J 0
(-8475 3225);
DISPLAY 1.021277 (-8475 3225);
DISPLAY INVISIBLE (-8475 3225);
FORCEADD TAP..1
(-6125 3675);
FORCEPROP 3 LASTPIN (-6175 3675) SIG_NAME M_F_CPU1_SB_DQ<27>
J 0
(-6165 3685);
DISPLAY 0.659574 (-6165 3685);
PAINT MONO (-6165 3685);
DISPLAY INVISIBLE (-6165 3685);
FORCEPROP 1 LASTPIN (-6175 3675) BN 27
J 0
(-6187 3683);
DISPLAY 0.489362 (-6187 3683);
PAINT GREEN (-6187 3683);
FORCEPROP 2 LAST CDS_LIB mstr_standard
J 0
(-6125 3675);
DISPLAY 0.723404 (-6125 3675);
PAINT MONO (-6125 3675);
DISPLAY INVISIBLE (-6125 3675);
FORCEPROP 1 LAST BODY_TYPE PLUMBING
J 0
(-6125 3725);
DISPLAY 0.872340 (-6125 3725);
PAINT GREEN (-6125 3725);
DISPLAY INVISIBLE (-6125 3725);
FORCEPROP 1 LAST HDL_TAP TRUE
J 0
(-5800 3550);
DISPLAY 0.872340 (-5800 3550);
DISPLAY INVISIBLE (-5800 3550);
FORCEPROP 1 LAST PATH I60
J 0
(-6127 3675);
DISPLAY 0.872340 (-6127 3675);
PAINT GREEN (-6127 3675);
DISPLAY INVISIBLE (-6127 3675);
FORCEADD TAP..1
(-6125 3625);
FORCEPROP 3 LASTPIN (-6175 3625) SIG_NAME M_F_CPU1_SB_DQ<26>
J 0
(-6165 3635);
DISPLAY 0.659574 (-6165 3635);
PAINT MONO (-6165 3635);
DISPLAY INVISIBLE (-6165 3635);
FORCEPROP 1 LASTPIN (-6175 3625) BN 26
J 0
(-6187 3633);
DISPLAY 0.489362 (-6187 3633);
PAINT GREEN (-6187 3633);
FORCEPROP 2 LAST CDS_LIB mstr_standard
J 0
(-6125 3625);
DISPLAY 0.723404 (-6125 3625);
PAINT MONO (-6125 3625);
DISPLAY INVISIBLE (-6125 3625);
FORCEPROP 1 LAST BODY_TYPE PLUMBING
J 0
(-6125 3675);
DISPLAY 0.872340 (-6125 3675);
PAINT GREEN (-6125 3675);
DISPLAY INVISIBLE (-6125 3675);
FORCEPROP 1 LAST HDL_TAP TRUE
J 0
(-5800 3500);
DISPLAY 0.872340 (-5800 3500);
DISPLAY INVISIBLE (-5800 3500);
FORCEPROP 1 LAST PATH I61
J 0
(-6127 3625);
DISPLAY 0.872340 (-6127 3625);
PAINT GREEN (-6127 3625);
DISPLAY INVISIBLE (-6127 3625);
FORCEADD TAP..1
(-6125 3475);
FORCEPROP 3 LASTPIN (-6175 3475) SIG_NAME M_F_CPU1_SB_DQ<23>
J 0
(-6165 3485);
DISPLAY 0.659574 (-6165 3485);
PAINT MONO (-6165 3485);
DISPLAY INVISIBLE (-6165 3485);
FORCEPROP 1 LASTPIN (-6175 3475) BN 23
J 0
(-6187 3483);
DISPLAY 0.489362 (-6187 3483);
PAINT GREEN (-6187 3483);
FORCEPROP 2 LAST CDS_LIB mstr_standard
J 0
(-6125 3475);
DISPLAY 0.723404 (-6125 3475);
PAINT MONO (-6125 3475);
DISPLAY INVISIBLE (-6125 3475);
FORCEPROP 1 LAST BODY_TYPE PLUMBING
J 0
(-6125 3525);
DISPLAY 0.872340 (-6125 3525);
PAINT GREEN (-6125 3525);
DISPLAY INVISIBLE (-6125 3525);
FORCEPROP 1 LAST HDL_TAP TRUE
J 0
(-5800 3350);
DISPLAY 0.872340 (-5800 3350);
DISPLAY INVISIBLE (-5800 3350);
FORCEPROP 1 LAST PATH I62
J 0
(-6127 3475);
DISPLAY 0.872340 (-6127 3475);
PAINT GREEN (-6127 3475);
DISPLAY INVISIBLE (-6127 3475);
FORCEADD TAP..1
(-6125 3775);
FORCEPROP 3 LASTPIN (-6175 3775) SIG_NAME M_F_CPU1_SB_DQ<29>
J 0
(-6165 3785);
DISPLAY 0.659574 (-6165 3785);
PAINT MONO (-6165 3785);
DISPLAY INVISIBLE (-6165 3785);
FORCEPROP 1 LASTPIN (-6175 3775) BN 29
J 0
(-6187 3783);
DISPLAY 0.489362 (-6187 3783);
PAINT GREEN (-6187 3783);
FORCEPROP 2 LAST CDS_LIB mstr_standard
J 0
(-6125 3775);
DISPLAY 0.723404 (-6125 3775);
PAINT MONO (-6125 3775);
DISPLAY INVISIBLE (-6125 3775);
FORCEPROP 1 LAST BODY_TYPE PLUMBING
J 0
(-6125 3825);
DISPLAY 0.872340 (-6125 3825);
PAINT GREEN (-6125 3825);
DISPLAY INVISIBLE (-6125 3825);
FORCEPROP 1 LAST HDL_TAP TRUE
J 0
(-5800 3650);
DISPLAY 0.872340 (-5800 3650);
DISPLAY INVISIBLE (-5800 3650);
FORCEPROP 1 LAST PATH I63
J 0
(-6127 3775);
DISPLAY 0.872340 (-6127 3775);
PAINT GREEN (-6127 3775);
DISPLAY INVISIBLE (-6127 3775);
FORCEADD TAP..1
(-6125 3875);
FORCEPROP 3 LASTPIN (-6175 3875) SIG_NAME M_F_CPU1_SB_DQ<31>
J 0
(-6165 3885);
DISPLAY 0.659574 (-6165 3885);
PAINT MONO (-6165 3885);
DISPLAY INVISIBLE (-6165 3885);
FORCEPROP 1 LASTPIN (-6175 3875) BN 31
J 0
(-6187 3883);
DISPLAY 0.489362 (-6187 3883);
PAINT GREEN (-6187 3883);
FORCEPROP 2 LAST CDS_LIB mstr_standard
J 0
(-6125 3875);
DISPLAY 0.723404 (-6125 3875);
PAINT MONO (-6125 3875);
DISPLAY INVISIBLE (-6125 3875);
FORCEPROP 1 LAST BODY_TYPE PLUMBING
J 0
(-6125 3925);
DISPLAY 0.872340 (-6125 3925);
PAINT GREEN (-6125 3925);
DISPLAY INVISIBLE (-6125 3925);
FORCEPROP 1 LAST HDL_TAP TRUE
J 0
(-5800 3750);
DISPLAY 0.872340 (-5800 3750);
DISPLAY INVISIBLE (-5800 3750);
FORCEPROP 1 LAST PATH I64
J 0
(-6127 3875);
DISPLAY 0.872340 (-6127 3875);
PAINT GREEN (-6127 3875);
DISPLAY INVISIBLE (-6127 3875);
FORCEADD TAP..1
(-6125 3825);
FORCEPROP 3 LASTPIN (-6175 3825) SIG_NAME M_F_CPU1_SB_DQ<30>
J 0
(-6165 3835);
DISPLAY 0.659574 (-6165 3835);
PAINT MONO (-6165 3835);
DISPLAY INVISIBLE (-6165 3835);
FORCEPROP 1 LASTPIN (-6175 3825) BN 30
J 0
(-6187 3833);
DISPLAY 0.489362 (-6187 3833);
PAINT GREEN (-6187 3833);
FORCEPROP 2 LAST CDS_LIB mstr_standard
J 0
(-6125 3825);
DISPLAY 0.723404 (-6125 3825);
PAINT MONO (-6125 3825);
DISPLAY INVISIBLE (-6125 3825);
FORCEPROP 1 LAST BODY_TYPE PLUMBING
J 0
(-6125 3875);
DISPLAY 0.872340 (-6125 3875);
PAINT GREEN (-6125 3875);
DISPLAY INVISIBLE (-6125 3875);
FORCEPROP 1 LAST HDL_TAP TRUE
J 0
(-5800 3700);
DISPLAY 0.872340 (-5800 3700);
DISPLAY INVISIBLE (-5800 3700);
FORCEPROP 1 LAST PATH I65
J 0
(-6127 3825);
DISPLAY 0.872340 (-6127 3825);
PAINT GREEN (-6127 3825);
DISPLAY INVISIBLE (-6127 3825);
FORCEADD TAP..1
(-6125 3725);
FORCEPROP 3 LASTPIN (-6175 3725) SIG_NAME M_F_CPU1_SB_DQ<28>
J 0
(-6165 3735);
DISPLAY 0.659574 (-6165 3735);
PAINT MONO (-6165 3735);
DISPLAY INVISIBLE (-6165 3735);
FORCEPROP 1 LASTPIN (-6175 3725) BN 28
J 0
(-6187 3733);
DISPLAY 0.489362 (-6187 3733);
PAINT GREEN (-6187 3733);
FORCEPROP 2 LAST CDS_LIB mstr_standard
J 0
(-6125 3725);
DISPLAY 0.723404 (-6125 3725);
PAINT MONO (-6125 3725);
DISPLAY INVISIBLE (-6125 3725);
FORCEPROP 1 LAST BODY_TYPE PLUMBING
J 0
(-6125 3775);
DISPLAY 0.872340 (-6125 3775);
PAINT GREEN (-6125 3775);
DISPLAY INVISIBLE (-6125 3775);
FORCEPROP 1 LAST HDL_TAP TRUE
J 0
(-5800 3600);
DISPLAY 0.872340 (-5800 3600);
DISPLAY INVISIBLE (-5800 3600);
FORCEPROP 1 LAST PATH I66
J 0
(-6127 3725);
DISPLAY 0.872340 (-6127 3725);
PAINT GREEN (-6127 3725);
DISPLAY INVISIBLE (-6127 3725);
FORCEADD OFFPAGE..3
(-5375 3925);
FORCEPROP 2 LAST $XR0 42 
J 0
(-5161 3925);
DISPLAY 0.638298 (-5161 3925);
PAINT MONO (-5161 3925);
FORCEPROP 2 LAST CDS_LIB mstr_standard
J 0
(-5375 3925);
DISPLAY 0.723404 (-5375 3925);
PAINT MONO (-5375 3925);
DISPLAY INVISIBLE (-5375 3925);
FORCEPROP 1 LAST OFFPAGE TRUE
J 0
(-5050 3800);
DISPLAY 0.872340 (-5050 3800);
PAINT GREEN (-5050 3800);
DISPLAY INVISIBLE (-5050 3800);
FORCEPROP 1 LAST COMMENT_BODY TRUE
J 0
(-5425 3825);
DISPLAY 0.872340 (-5425 3825);
PAINT GREEN (-5425 3825);
DISPLAY INVISIBLE (-5425 3825);
FORCEPROP 2 LAST PATH I73
J 0
(-5150 3975);
DISPLAY 1.021277 (-5150 3975);
DISPLAY INVISIBLE (-5150 3975);
FORCEADD TAP..1
R 2
(-7825 3975);
FORCEPROP 3 LASTPIN (-7775 3975) SIG_NAME M_F_CPU1_SA_CB<4>
J 0
(-7765 3985);
DISPLAY 0.659574 (-7765 3985);
PAINT MONO (-7765 3985);
DISPLAY INVISIBLE (-7765 3985);
FORCEPROP 1 LASTPIN (-7775 3975) BN 4
J 2
(-7763 3983);
DISPLAY 0.489362 (-7763 3983);
PAINT GREEN (-7763 3983);
FORCEPROP 2 LAST CDS_LIB mstr_standard
J 0
(-7825 3975);
DISPLAY 0.723404 (-7825 3975);
PAINT MONO (-7825 3975);
DISPLAY INVISIBLE (-7825 3975);
FORCEPROP 1 LAST BODY_TYPE PLUMBING
J 2
(-7825 4025);
DISPLAY 0.872340 (-7825 4025);
PAINT GREEN (-7825 4025);
DISPLAY INVISIBLE (-7825 4025);
FORCEPROP 1 LAST HDL_TAP TRUE
J 2
(-8150 3850);
DISPLAY 0.872340 (-8150 3850);
DISPLAY INVISIBLE (-8150 3850);
FORCEPROP 1 LAST PATH I76
J 2
(-7823 3975);
DISPLAY 0.872340 (-7823 3975);
PAINT GREEN (-7823 3975);
DISPLAY INVISIBLE (-7823 3975);
FORCEADD TAP..1
R 2
(-7825 4025);
FORCEPROP 3 LASTPIN (-7775 4025) SIG_NAME M_F_CPU1_SA_CB<5>
J 0
(-7765 4035);
DISPLAY 0.659574 (-7765 4035);
PAINT MONO (-7765 4035);
DISPLAY INVISIBLE (-7765 4035);
FORCEPROP 1 LASTPIN (-7775 4025) BN 5
J 2
(-7763 4033);
DISPLAY 0.489362 (-7763 4033);
PAINT GREEN (-7763 4033);
FORCEPROP 2 LAST CDS_LIB mstr_standard
J 0
(-7825 4025);
DISPLAY 0.723404 (-7825 4025);
PAINT MONO (-7825 4025);
DISPLAY INVISIBLE (-7825 4025);
FORCEPROP 1 LAST BODY_TYPE PLUMBING
J 2
(-7825 4075);
DISPLAY 0.872340 (-7825 4075);
PAINT GREEN (-7825 4075);
DISPLAY INVISIBLE (-7825 4075);
FORCEPROP 1 LAST HDL_TAP TRUE
J 2
(-8150 3900);
DISPLAY 0.872340 (-8150 3900);
DISPLAY INVISIBLE (-8150 3900);
FORCEPROP 1 LAST PATH I77
J 2
(-7823 4025);
DISPLAY 0.872340 (-7823 4025);
PAINT GREEN (-7823 4025);
DISPLAY INVISIBLE (-7823 4025);
FORCEADD TAP..1
R 2
(-7825 4125);
FORCEPROP 3 LASTPIN (-7775 4125) SIG_NAME M_F_CPU1_SA_CB<7>
J 0
(-7765 4135);
DISPLAY 0.659574 (-7765 4135);
PAINT MONO (-7765 4135);
DISPLAY INVISIBLE (-7765 4135);
FORCEPROP 1 LASTPIN (-7775 4125) BN 7
J 2
(-7763 4133);
DISPLAY 0.489362 (-7763 4133);
PAINT GREEN (-7763 4133);
FORCEPROP 2 LAST CDS_LIB mstr_standard
J 0
(-7825 4125);
DISPLAY 0.723404 (-7825 4125);
PAINT MONO (-7825 4125);
DISPLAY INVISIBLE (-7825 4125);
FORCEPROP 1 LAST BODY_TYPE PLUMBING
J 2
(-7825 4175);
DISPLAY 0.872340 (-7825 4175);
PAINT GREEN (-7825 4175);
DISPLAY INVISIBLE (-7825 4175);
FORCEPROP 1 LAST HDL_TAP TRUE
J 2
(-8150 4000);
DISPLAY 0.872340 (-8150 4000);
DISPLAY INVISIBLE (-8150 4000);
FORCEPROP 1 LAST PATH I78
J 2
(-7823 4125);
DISPLAY 0.872340 (-7823 4125);
PAINT GREEN (-7823 4125);
DISPLAY INVISIBLE (-7823 4125);
FORCEADD TAP..1
R 2
(-7825 4075);
FORCEPROP 3 LASTPIN (-7775 4075) SIG_NAME M_F_CPU1_SA_CB<6>
J 0
(-7765 4085);
DISPLAY 0.659574 (-7765 4085);
PAINT MONO (-7765 4085);
DISPLAY INVISIBLE (-7765 4085);
FORCEPROP 1 LASTPIN (-7775 4075) BN 6
J 2
(-7763 4083);
DISPLAY 0.489362 (-7763 4083);
PAINT GREEN (-7763 4083);
FORCEPROP 2 LAST CDS_LIB mstr_standard
J 0
(-7825 4075);
DISPLAY 0.723404 (-7825 4075);
PAINT MONO (-7825 4075);
DISPLAY INVISIBLE (-7825 4075);
FORCEPROP 1 LAST BODY_TYPE PLUMBING
J 2
(-7825 4125);
DISPLAY 0.872340 (-7825 4125);
PAINT GREEN (-7825 4125);
DISPLAY INVISIBLE (-7825 4125);
FORCEPROP 1 LAST HDL_TAP TRUE
J 2
(-8150 3950);
DISPLAY 0.872340 (-8150 3950);
DISPLAY INVISIBLE (-8150 3950);
FORCEPROP 1 LAST PATH I79
J 2
(-7823 4075);
DISPLAY 0.872340 (-7823 4075);
PAINT GREEN (-7823 4075);
DISPLAY INVISIBLE (-7823 4075);
FORCEADD OFFPAGE..1
(-8800 3025);
FORCEPROP 2 LAST $XR0 103 
J 0
(-9082 3025);
DISPLAY 0.638298 (-9082 3025);
PAINT MONO (-9082 3025);
FORCEPROP 2 LAST CDS_LIB mstr_standard
J 0
(-8800 3025);
DISPLAY 0.808511 (-8800 3025);
DISPLAY INVISIBLE (-8800 3025);
FORCEPROP 1 LAST OFFPAGE TRUE
J 0
(-8475 2900);
DISPLAY 0.872340 (-8475 2900);
PAINT GREEN (-8475 2900);
DISPLAY INVISIBLE (-8475 2900);
FORCEPROP 1 LAST COMMENT_BODY TRUE
J 0
(-8675 2925);
DISPLAY 0.872340 (-8675 2925);
PAINT GREEN (-8675 2925);
DISPLAY INVISIBLE (-8675 2925);
FORCEPROP 2 LAST PATH I8
J 0
(-9050 3075);
DISPLAY 1.021277 (-9050 3075);
DISPLAY INVISIBLE (-9050 3075);
FORCEADD TAP..1
R 2
(-7825 4825);
FORCEPROP 3 LASTPIN (-7775 4825) SIG_NAME M_F_CPU1_SB_CA<0>
J 0
(-7765 4835);
DISPLAY 0.659574 (-7765 4835);
PAINT MONO (-7765 4835);
DISPLAY INVISIBLE (-7765 4835);
FORCEPROP 1 LASTPIN (-7775 4825) BN 0
J 2
(-7763 4833);
DISPLAY 0.489362 (-7763 4833);
PAINT GREEN (-7763 4833);
FORCEPROP 2 LAST CDS_LIB mstr_standard
J 0
(-7825 4825);
DISPLAY 0.723404 (-7825 4825);
PAINT MONO (-7825 4825);
DISPLAY INVISIBLE (-7825 4825);
FORCEPROP 1 LAST BODY_TYPE PLUMBING
J 2
(-7825 4875);
DISPLAY 0.872340 (-7825 4875);
PAINT GREEN (-7825 4875);
DISPLAY INVISIBLE (-7825 4875);
FORCEPROP 1 LAST HDL_TAP TRUE
J 2
(-8150 4700);
DISPLAY 0.872340 (-8150 4700);
DISPLAY INVISIBLE (-8150 4700);
FORCEPROP 1 LAST PATH I80
J 2
(-7823 4825);
DISPLAY 0.872340 (-7823 4825);
PAINT GREEN (-7823 4825);
DISPLAY INVISIBLE (-7823 4825);
FORCEADD TAP..1
R 2
(-7825 4875);
FORCEPROP 3 LASTPIN (-7775 4875) SIG_NAME M_F_CPU1_SB_CA<1>
J 0
(-7765 4885);
DISPLAY 0.659574 (-7765 4885);
PAINT MONO (-7765 4885);
DISPLAY INVISIBLE (-7765 4885);
FORCEPROP 1 LASTPIN (-7775 4875) BN 1
J 2
(-7763 4883);
DISPLAY 0.489362 (-7763 4883);
PAINT GREEN (-7763 4883);
FORCEPROP 2 LAST CDS_LIB mstr_standard
J 0
(-7825 4875);
DISPLAY 0.723404 (-7825 4875);
PAINT MONO (-7825 4875);
DISPLAY INVISIBLE (-7825 4875);
FORCEPROP 1 LAST BODY_TYPE PLUMBING
J 2
(-7825 4925);
DISPLAY 0.872340 (-7825 4925);
PAINT GREEN (-7825 4925);
DISPLAY INVISIBLE (-7825 4925);
FORCEPROP 1 LAST HDL_TAP TRUE
J 2
(-8150 4750);
DISPLAY 0.872340 (-8150 4750);
DISPLAY INVISIBLE (-8150 4750);
FORCEPROP 1 LAST PATH I81
J 2
(-7823 4875);
DISPLAY 0.872340 (-7823 4875);
PAINT GREEN (-7823 4875);
DISPLAY INVISIBLE (-7823 4875);
FORCEADD TAP..1
R 2
(-7825 4925);
FORCEPROP 3 LASTPIN (-7775 4925) SIG_NAME M_F_CPU1_SB_CA<2>
J 0
(-7765 4935);
DISPLAY 0.659574 (-7765 4935);
PAINT MONO (-7765 4935);
DISPLAY INVISIBLE (-7765 4935);
FORCEPROP 1 LASTPIN (-7775 4925) BN 2
J 2
(-7763 4933);
DISPLAY 0.489362 (-7763 4933);
PAINT GREEN (-7763 4933);
FORCEPROP 2 LAST CDS_LIB mstr_standard
J 0
(-7825 4925);
DISPLAY 0.723404 (-7825 4925);
PAINT MONO (-7825 4925);
DISPLAY INVISIBLE (-7825 4925);
FORCEPROP 1 LAST BODY_TYPE PLUMBING
J 2
(-7825 4975);
DISPLAY 0.872340 (-7825 4975);
PAINT GREEN (-7825 4975);
DISPLAY INVISIBLE (-7825 4975);
FORCEPROP 1 LAST HDL_TAP TRUE
J 2
(-8150 4800);
DISPLAY 0.872340 (-8150 4800);
DISPLAY INVISIBLE (-8150 4800);
FORCEPROP 1 LAST PATH I82
J 2
(-7823 4925);
DISPLAY 0.872340 (-7823 4925);
PAINT GREEN (-7823 4925);
DISPLAY INVISIBLE (-7823 4925);
FORCEADD TAP..1
R 2
(-7825 5025);
FORCEPROP 3 LASTPIN (-7775 5025) SIG_NAME M_F_CPU1_SB_CA<4>
J 0
(-7765 5035);
DISPLAY 0.659574 (-7765 5035);
PAINT MONO (-7765 5035);
DISPLAY INVISIBLE (-7765 5035);
FORCEPROP 1 LASTPIN (-7775 5025) BN 4
J 2
(-7763 5033);
DISPLAY 0.489362 (-7763 5033);
PAINT GREEN (-7763 5033);
FORCEPROP 2 LAST CDS_LIB mstr_standard
J 0
(-7825 5025);
DISPLAY 0.723404 (-7825 5025);
PAINT MONO (-7825 5025);
DISPLAY INVISIBLE (-7825 5025);
FORCEPROP 1 LAST BODY_TYPE PLUMBING
J 2
(-7825 5075);
DISPLAY 0.872340 (-7825 5075);
PAINT GREEN (-7825 5075);
DISPLAY INVISIBLE (-7825 5075);
FORCEPROP 1 LAST HDL_TAP TRUE
J 2
(-8150 4900);
DISPLAY 0.872340 (-8150 4900);
DISPLAY INVISIBLE (-8150 4900);
FORCEPROP 1 LAST PATH I83
J 2
(-7823 5025);
DISPLAY 0.872340 (-7823 5025);
PAINT GREEN (-7823 5025);
DISPLAY INVISIBLE (-7823 5025);
FORCEADD TAP..1
R 2
(-7825 4975);
FORCEPROP 3 LASTPIN (-7775 4975) SIG_NAME M_F_CPU1_SB_CA<3>
J 0
(-7765 4985);
DISPLAY 0.659574 (-7765 4985);
PAINT MONO (-7765 4985);
DISPLAY INVISIBLE (-7765 4985);
FORCEPROP 1 LASTPIN (-7775 4975) BN 3
J 2
(-7763 4983);
DISPLAY 0.489362 (-7763 4983);
PAINT GREEN (-7763 4983);
FORCEPROP 2 LAST CDS_LIB mstr_standard
J 0
(-7825 4975);
DISPLAY 0.723404 (-7825 4975);
PAINT MONO (-7825 4975);
DISPLAY INVISIBLE (-7825 4975);
FORCEPROP 1 LAST BODY_TYPE PLUMBING
J 2
(-7825 5025);
DISPLAY 0.872340 (-7825 5025);
PAINT GREEN (-7825 5025);
DISPLAY INVISIBLE (-7825 5025);
FORCEPROP 1 LAST HDL_TAP TRUE
J 2
(-8150 4850);
DISPLAY 0.872340 (-8150 4850);
DISPLAY INVISIBLE (-8150 4850);
FORCEPROP 1 LAST PATH I84
J 2
(-7823 4975);
DISPLAY 0.872340 (-7823 4975);
PAINT GREEN (-7823 4975);
DISPLAY INVISIBLE (-7823 4975);
FORCEADD TAP..1
R 2
(-7825 5075);
FORCEPROP 3 LASTPIN (-7775 5075) SIG_NAME M_F_CPU1_SB_CA<5>
J 0
(-7765 5085);
DISPLAY 0.659574 (-7765 5085);
PAINT MONO (-7765 5085);
DISPLAY INVISIBLE (-7765 5085);
FORCEPROP 1 LASTPIN (-7775 5075) BN 5
J 2
(-7763 5083);
DISPLAY 0.489362 (-7763 5083);
PAINT GREEN (-7763 5083);
FORCEPROP 2 LAST CDS_LIB mstr_standard
J 0
(-7825 5075);
DISPLAY 0.723404 (-7825 5075);
PAINT MONO (-7825 5075);
DISPLAY INVISIBLE (-7825 5075);
FORCEPROP 1 LAST BODY_TYPE PLUMBING
J 2
(-7825 5125);
DISPLAY 0.872340 (-7825 5125);
PAINT GREEN (-7825 5125);
DISPLAY INVISIBLE (-7825 5125);
FORCEPROP 1 LAST HDL_TAP TRUE
J 2
(-8150 4950);
DISPLAY 0.872340 (-8150 4950);
DISPLAY INVISIBLE (-8150 4950);
FORCEPROP 1 LAST PATH I85
J 2
(-7823 5075);
DISPLAY 0.872340 (-7823 5075);
PAINT GREEN (-7823 5075);
DISPLAY INVISIBLE (-7823 5075);
FORCEADD TAP..1
R 2
(-7825 5125);
FORCEPROP 3 LASTPIN (-7775 5125) SIG_NAME M_F_CPU1_SB_CA<6>
J 0
(-7765 5135);
DISPLAY 0.659574 (-7765 5135);
PAINT MONO (-7765 5135);
DISPLAY INVISIBLE (-7765 5135);
FORCEPROP 1 LASTPIN (-7775 5125) BN 6
J 2
(-7763 5133);
DISPLAY 0.489362 (-7763 5133);
PAINT GREEN (-7763 5133);
FORCEPROP 2 LAST CDS_LIB mstr_standard
J 0
(-7825 5125);
DISPLAY 0.723404 (-7825 5125);
PAINT MONO (-7825 5125);
DISPLAY INVISIBLE (-7825 5125);
FORCEPROP 1 LAST BODY_TYPE PLUMBING
J 2
(-7825 5175);
DISPLAY 0.872340 (-7825 5175);
PAINT GREEN (-7825 5175);
DISPLAY INVISIBLE (-7825 5175);
FORCEPROP 1 LAST HDL_TAP TRUE
J 2
(-8150 5000);
DISPLAY 0.872340 (-8150 5000);
DISPLAY INVISIBLE (-8150 5000);
FORCEPROP 1 LAST PATH I86
J 2
(-7823 5125);
DISPLAY 0.872340 (-7823 5125);
PAINT GREEN (-7823 5125);
DISPLAY INVISIBLE (-7823 5125);
FORCEADD TAP..1
R 2
(-7825 5225);
FORCEPROP 3 LASTPIN (-7775 5225) SIG_NAME M_F_CPU1_SA_CA<0>
J 0
(-7765 5235);
DISPLAY 0.659574 (-7765 5235);
PAINT MONO (-7765 5235);
DISPLAY INVISIBLE (-7765 5235);
FORCEPROP 1 LASTPIN (-7775 5225) BN 0
J 2
(-7763 5233);
DISPLAY 0.489362 (-7763 5233);
PAINT GREEN (-7763 5233);
FORCEPROP 2 LAST CDS_LIB mstr_standard
J 0
(-7825 5225);
DISPLAY 0.723404 (-7825 5225);
PAINT MONO (-7825 5225);
DISPLAY INVISIBLE (-7825 5225);
FORCEPROP 1 LAST BODY_TYPE PLUMBING
J 2
(-7825 5275);
DISPLAY 0.872340 (-7825 5275);
PAINT GREEN (-7825 5275);
DISPLAY INVISIBLE (-7825 5275);
FORCEPROP 1 LAST HDL_TAP TRUE
J 2
(-8150 5100);
DISPLAY 0.872340 (-8150 5100);
DISPLAY INVISIBLE (-8150 5100);
FORCEPROP 1 LAST PATH I87
J 2
(-7823 5225);
DISPLAY 0.872340 (-7823 5225);
PAINT GREEN (-7823 5225);
DISPLAY INVISIBLE (-7823 5225);
FORCEADD TAP..1
R 2
(-7825 5275);
FORCEPROP 3 LASTPIN (-7775 5275) SIG_NAME M_F_CPU1_SA_CA<1>
J 0
(-7765 5285);
DISPLAY 0.659574 (-7765 5285);
PAINT MONO (-7765 5285);
DISPLAY INVISIBLE (-7765 5285);
FORCEPROP 1 LASTPIN (-7775 5275) BN 1
J 2
(-7763 5283);
DISPLAY 0.489362 (-7763 5283);
PAINT GREEN (-7763 5283);
FORCEPROP 2 LAST CDS_LIB mstr_standard
J 0
(-7825 5275);
DISPLAY 0.723404 (-7825 5275);
PAINT MONO (-7825 5275);
DISPLAY INVISIBLE (-7825 5275);
FORCEPROP 1 LAST BODY_TYPE PLUMBING
J 2
(-7825 5325);
DISPLAY 0.872340 (-7825 5325);
PAINT GREEN (-7825 5325);
DISPLAY INVISIBLE (-7825 5325);
FORCEPROP 1 LAST HDL_TAP TRUE
J 2
(-8150 5150);
DISPLAY 0.872340 (-8150 5150);
DISPLAY INVISIBLE (-8150 5150);
FORCEPROP 1 LAST PATH I88
J 2
(-7823 5275);
DISPLAY 0.872340 (-7823 5275);
PAINT GREEN (-7823 5275);
DISPLAY INVISIBLE (-7823 5275);
FORCEADD TAP..1
R 2
(-7825 5325);
FORCEPROP 3 LASTPIN (-7775 5325) SIG_NAME M_F_CPU1_SA_CA<2>
J 0
(-7765 5335);
DISPLAY 0.659574 (-7765 5335);
PAINT MONO (-7765 5335);
DISPLAY INVISIBLE (-7765 5335);
FORCEPROP 1 LASTPIN (-7775 5325) BN 2
J 2
(-7763 5333);
DISPLAY 0.489362 (-7763 5333);
PAINT GREEN (-7763 5333);
FORCEPROP 2 LAST CDS_LIB mstr_standard
J 0
(-7825 5325);
DISPLAY 0.723404 (-7825 5325);
PAINT MONO (-7825 5325);
DISPLAY INVISIBLE (-7825 5325);
FORCEPROP 1 LAST BODY_TYPE PLUMBING
J 2
(-7825 5375);
DISPLAY 0.872340 (-7825 5375);
PAINT GREEN (-7825 5375);
DISPLAY INVISIBLE (-7825 5375);
FORCEPROP 1 LAST HDL_TAP TRUE
J 2
(-8150 5200);
DISPLAY 0.872340 (-8150 5200);
DISPLAY INVISIBLE (-8150 5200);
FORCEPROP 1 LAST PATH I89
J 2
(-7823 5325);
DISPLAY 0.872340 (-7823 5325);
PAINT GREEN (-7823 5325);
DISPLAY INVISIBLE (-7823 5325);
FORCEADD OFFPAGE..1
(-8225 3225);
FORCEPROP 2 LAST $XR0 42 
J 0
(-8476 3225);
DISPLAY 0.638298 (-8476 3225);
PAINT MONO (-8476 3225);
FORCEPROP 2 LAST CDS_LIB mstr_standard
J 0
(-8225 3225);
DISPLAY 0.808511 (-8225 3225);
DISPLAY INVISIBLE (-8225 3225);
FORCEPROP 1 LAST OFFPAGE TRUE
J 0
(-7900 3100);
DISPLAY 0.872340 (-7900 3100);
PAINT GREEN (-7900 3100);
DISPLAY INVISIBLE (-7900 3100);
FORCEPROP 1 LAST COMMENT_BODY TRUE
J 0
(-8100 3125);
DISPLAY 0.872340 (-8100 3125);
PAINT GREEN (-8100 3125);
DISPLAY INVISIBLE (-8100 3125);
FORCEPROP 2 LAST PATH I9
J 0
(-8425 3275);
DISPLAY 1.021277 (-8425 3275);
DISPLAY INVISIBLE (-8425 3275);
FORCEADD TAP..1
R 2
(-7825 5375);
FORCEPROP 3 LASTPIN (-7775 5375) SIG_NAME M_F_CPU1_SA_CA<3>
J 0
(-7765 5385);
DISPLAY 0.659574 (-7765 5385);
PAINT MONO (-7765 5385);
DISPLAY INVISIBLE (-7765 5385);
FORCEPROP 1 LASTPIN (-7775 5375) BN 3
J 2
(-7763 5383);
DISPLAY 0.489362 (-7763 5383);
PAINT GREEN (-7763 5383);
FORCEPROP 2 LAST CDS_LIB mstr_standard
J 0
(-7825 5375);
DISPLAY 0.723404 (-7825 5375);
PAINT MONO (-7825 5375);
DISPLAY INVISIBLE (-7825 5375);
FORCEPROP 1 LAST BODY_TYPE PLUMBING
J 2
(-7825 5425);
DISPLAY 0.872340 (-7825 5425);
PAINT GREEN (-7825 5425);
DISPLAY INVISIBLE (-7825 5425);
FORCEPROP 1 LAST HDL_TAP TRUE
J 2
(-8150 5250);
DISPLAY 0.872340 (-8150 5250);
DISPLAY INVISIBLE (-8150 5250);
FORCEPROP 1 LAST PATH I90
J 2
(-7823 5375);
DISPLAY 0.872340 (-7823 5375);
PAINT GREEN (-7823 5375);
DISPLAY INVISIBLE (-7823 5375);
FORCEADD TAP..1
R 2
(-7825 5425);
FORCEPROP 3 LASTPIN (-7775 5425) SIG_NAME M_F_CPU1_SA_CA<4>
J 0
(-7765 5435);
DISPLAY 0.659574 (-7765 5435);
PAINT MONO (-7765 5435);
DISPLAY INVISIBLE (-7765 5435);
FORCEPROP 1 LASTPIN (-7775 5425) BN 4
J 2
(-7763 5433);
DISPLAY 0.489362 (-7763 5433);
PAINT GREEN (-7763 5433);
FORCEPROP 2 LAST CDS_LIB mstr_standard
J 0
(-7825 5425);
DISPLAY 0.723404 (-7825 5425);
PAINT MONO (-7825 5425);
DISPLAY INVISIBLE (-7825 5425);
FORCEPROP 1 LAST BODY_TYPE PLUMBING
J 2
(-7825 5475);
DISPLAY 0.872340 (-7825 5475);
PAINT GREEN (-7825 5475);
DISPLAY INVISIBLE (-7825 5475);
FORCEPROP 1 LAST HDL_TAP TRUE
J 2
(-8150 5300);
DISPLAY 0.872340 (-8150 5300);
DISPLAY INVISIBLE (-8150 5300);
FORCEPROP 1 LAST PATH I91
J 2
(-7823 5425);
DISPLAY 0.872340 (-7823 5425);
PAINT GREEN (-7823 5425);
DISPLAY INVISIBLE (-7823 5425);
FORCEADD TAP..1
R 2
(-7825 5475);
FORCEPROP 3 LASTPIN (-7775 5475) SIG_NAME M_F_CPU1_SA_CA<5>
J 0
(-7765 5485);
DISPLAY 0.659574 (-7765 5485);
PAINT MONO (-7765 5485);
DISPLAY INVISIBLE (-7765 5485);
FORCEPROP 1 LASTPIN (-7775 5475) BN 5
J 2
(-7763 5483);
DISPLAY 0.489362 (-7763 5483);
PAINT GREEN (-7763 5483);
FORCEPROP 2 LAST CDS_LIB mstr_standard
J 0
(-7825 5475);
DISPLAY 0.723404 (-7825 5475);
PAINT MONO (-7825 5475);
DISPLAY INVISIBLE (-7825 5475);
FORCEPROP 1 LAST BODY_TYPE PLUMBING
J 2
(-7825 5525);
DISPLAY 0.872340 (-7825 5525);
PAINT GREEN (-7825 5525);
DISPLAY INVISIBLE (-7825 5525);
FORCEPROP 1 LAST HDL_TAP TRUE
J 2
(-8150 5350);
DISPLAY 0.872340 (-8150 5350);
DISPLAY INVISIBLE (-8150 5350);
FORCEPROP 1 LAST PATH I92
J 2
(-7823 5475);
DISPLAY 0.872340 (-7823 5475);
PAINT GREEN (-7823 5475);
DISPLAY INVISIBLE (-7823 5475);
FORCEADD TAP..1
R 2
(-7825 5525);
FORCEPROP 3 LASTPIN (-7775 5525) SIG_NAME M_F_CPU1_SA_CA<6>
J 0
(-7765 5535);
DISPLAY 0.659574 (-7765 5535);
PAINT MONO (-7765 5535);
DISPLAY INVISIBLE (-7765 5535);
FORCEPROP 1 LASTPIN (-7775 5525) BN 6
J 2
(-7763 5533);
DISPLAY 0.489362 (-7763 5533);
PAINT GREEN (-7763 5533);
FORCEPROP 2 LAST CDS_LIB mstr_standard
J 0
(-7825 5525);
DISPLAY 0.723404 (-7825 5525);
PAINT MONO (-7825 5525);
DISPLAY INVISIBLE (-7825 5525);
FORCEPROP 1 LAST BODY_TYPE PLUMBING
J 2
(-7825 5575);
DISPLAY 0.872340 (-7825 5575);
PAINT GREEN (-7825 5575);
DISPLAY INVISIBLE (-7825 5575);
FORCEPROP 1 LAST HDL_TAP TRUE
J 2
(-8150 5400);
DISPLAY 0.872340 (-8150 5400);
DISPLAY INVISIBLE (-8150 5400);
FORCEPROP 1 LAST PATH I93
J 2
(-7823 5525);
DISPLAY 0.872340 (-7823 5525);
PAINT GREEN (-7823 5525);
DISPLAY INVISIBLE (-7823 5525);
FORCEADD TAP..1
(-6125 3975);
FORCEPROP 3 LASTPIN (-6175 3975) SIG_NAME M_F_CPU1_SA_DQ<0>
J 0
(-6165 3985);
DISPLAY 0.659574 (-6165 3985);
PAINT MONO (-6165 3985);
DISPLAY INVISIBLE (-6165 3985);
FORCEPROP 1 LASTPIN (-6175 3975) BN 0
J 0
(-6187 3983);
DISPLAY 0.489362 (-6187 3983);
PAINT GREEN (-6187 3983);
FORCEPROP 2 LAST CDS_LIB mstr_standard
J 0
(-6125 3975);
DISPLAY 0.723404 (-6125 3975);
PAINT MONO (-6125 3975);
DISPLAY INVISIBLE (-6125 3975);
FORCEPROP 1 LAST BODY_TYPE PLUMBING
J 0
(-6125 4025);
DISPLAY 0.872340 (-6125 4025);
PAINT GREEN (-6125 4025);
DISPLAY INVISIBLE (-6125 4025);
FORCEPROP 1 LAST HDL_TAP TRUE
J 0
(-5800 3850);
DISPLAY 0.872340 (-5800 3850);
DISPLAY INVISIBLE (-5800 3850);
FORCEPROP 1 LAST PATH I94
J 0
(-6127 3975);
DISPLAY 0.872340 (-6127 3975);
PAINT GREEN (-6127 3975);
DISPLAY INVISIBLE (-6127 3975);
FORCEADD TAP..1
(-6125 4025);
FORCEPROP 3 LASTPIN (-6175 4025) SIG_NAME M_F_CPU1_SA_DQ<1>
J 0
(-6165 4035);
DISPLAY 0.659574 (-6165 4035);
PAINT MONO (-6165 4035);
DISPLAY INVISIBLE (-6165 4035);
FORCEPROP 1 LASTPIN (-6175 4025) BN 1
J 0
(-6187 4033);
DISPLAY 0.489362 (-6187 4033);
PAINT GREEN (-6187 4033);
FORCEPROP 2 LAST CDS_LIB mstr_standard
J 0
(-6125 4025);
DISPLAY 0.723404 (-6125 4025);
PAINT MONO (-6125 4025);
DISPLAY INVISIBLE (-6125 4025);
FORCEPROP 1 LAST BODY_TYPE PLUMBING
J 0
(-6125 4075);
DISPLAY 0.872340 (-6125 4075);
PAINT GREEN (-6125 4075);
DISPLAY INVISIBLE (-6125 4075);
FORCEPROP 1 LAST HDL_TAP TRUE
J 0
(-5800 3900);
DISPLAY 0.872340 (-5800 3900);
DISPLAY INVISIBLE (-5800 3900);
FORCEPROP 1 LAST PATH I95
J 0
(-6127 4025);
DISPLAY 0.872340 (-6127 4025);
PAINT GREEN (-6127 4025);
DISPLAY INVISIBLE (-6127 4025);
FORCEADD TAP..1
(-6125 4075);
FORCEPROP 3 LASTPIN (-6175 4075) SIG_NAME M_F_CPU1_SA_DQ<2>
J 0
(-6165 4085);
DISPLAY 0.659574 (-6165 4085);
PAINT MONO (-6165 4085);
DISPLAY INVISIBLE (-6165 4085);
FORCEPROP 1 LASTPIN (-6175 4075) BN 2
J 0
(-6187 4083);
DISPLAY 0.489362 (-6187 4083);
PAINT GREEN (-6187 4083);
FORCEPROP 2 LAST CDS_LIB mstr_standard
J 0
(-6125 4075);
DISPLAY 0.723404 (-6125 4075);
PAINT MONO (-6125 4075);
DISPLAY INVISIBLE (-6125 4075);
FORCEPROP 1 LAST BODY_TYPE PLUMBING
J 0
(-6125 4125);
DISPLAY 0.872340 (-6125 4125);
PAINT GREEN (-6125 4125);
DISPLAY INVISIBLE (-6125 4125);
FORCEPROP 1 LAST HDL_TAP TRUE
J 0
(-5800 3950);
DISPLAY 0.872340 (-5800 3950);
DISPLAY INVISIBLE (-5800 3950);
FORCEPROP 1 LAST PATH I96
J 0
(-6127 4075);
DISPLAY 0.872340 (-6127 4075);
PAINT GREEN (-6127 4075);
DISPLAY INVISIBLE (-6127 4075);
FORCEADD TAP..1
(-6125 4125);
FORCEPROP 3 LASTPIN (-6175 4125) SIG_NAME M_F_CPU1_SA_DQ<3>
J 0
(-6165 4135);
DISPLAY 0.659574 (-6165 4135);
PAINT MONO (-6165 4135);
DISPLAY INVISIBLE (-6165 4135);
FORCEPROP 1 LASTPIN (-6175 4125) BN 3
J 0
(-6187 4133);
DISPLAY 0.489362 (-6187 4133);
PAINT GREEN (-6187 4133);
FORCEPROP 2 LAST CDS_LIB mstr_standard
J 0
(-6125 4125);
DISPLAY 0.723404 (-6125 4125);
PAINT MONO (-6125 4125);
DISPLAY INVISIBLE (-6125 4125);
FORCEPROP 1 LAST BODY_TYPE PLUMBING
J 0
(-6125 4175);
DISPLAY 0.872340 (-6125 4175);
PAINT GREEN (-6125 4175);
DISPLAY INVISIBLE (-6125 4175);
FORCEPROP 1 LAST HDL_TAP TRUE
J 0
(-5800 4000);
DISPLAY 0.872340 (-5800 4000);
DISPLAY INVISIBLE (-5800 4000);
FORCEPROP 1 LAST PATH I97
J 0
(-6127 4125);
DISPLAY 0.872340 (-6127 4125);
PAINT GREEN (-6127 4125);
DISPLAY INVISIBLE (-6127 4125);
FORCEADD TAP..1
(-6125 4175);
FORCEPROP 3 LASTPIN (-6175 4175) SIG_NAME M_F_CPU1_SA_DQ<4>
J 0
(-6165 4185);
DISPLAY 0.659574 (-6165 4185);
PAINT MONO (-6165 4185);
DISPLAY INVISIBLE (-6165 4185);
FORCEPROP 1 LASTPIN (-6175 4175) BN 4
J 0
(-6187 4183);
DISPLAY 0.489362 (-6187 4183);
PAINT GREEN (-6187 4183);
FORCEPROP 2 LAST CDS_LIB mstr_standard
J 0
(-6125 4175);
DISPLAY 0.723404 (-6125 4175);
PAINT MONO (-6125 4175);
DISPLAY INVISIBLE (-6125 4175);
FORCEPROP 1 LAST BODY_TYPE PLUMBING
J 0
(-6125 4225);
DISPLAY 0.872340 (-6125 4225);
PAINT GREEN (-6125 4225);
DISPLAY INVISIBLE (-6125 4225);
FORCEPROP 1 LAST HDL_TAP TRUE
J 0
(-5800 4050);
DISPLAY 0.872340 (-5800 4050);
DISPLAY INVISIBLE (-5800 4050);
FORCEPROP 1 LAST PATH I98
J 0
(-6127 4175);
DISPLAY 0.872340 (-6127 4175);
PAINT GREEN (-6127 4175);
DISPLAY INVISIBLE (-6127 4175);
FORCEADD TAP..1
(-6125 4225);
FORCEPROP 3 LASTPIN (-6175 4225) SIG_NAME M_F_CPU1_SA_DQ<5>
J 0
(-6165 4235);
DISPLAY 0.659574 (-6165 4235);
PAINT MONO (-6165 4235);
DISPLAY INVISIBLE (-6165 4235);
FORCEPROP 1 LASTPIN (-6175 4225) BN 5
J 0
(-6187 4233);
DISPLAY 0.489362 (-6187 4233);
PAINT GREEN (-6187 4233);
FORCEPROP 2 LAST CDS_LIB mstr_standard
J 0
(-6125 4225);
DISPLAY 0.723404 (-6125 4225);
PAINT MONO (-6125 4225);
DISPLAY INVISIBLE (-6125 4225);
FORCEPROP 1 LAST BODY_TYPE PLUMBING
J 0
(-6125 4275);
DISPLAY 0.872340 (-6125 4275);
PAINT GREEN (-6125 4275);
DISPLAY INVISIBLE (-6125 4275);
FORCEPROP 1 LAST HDL_TAP TRUE
J 0
(-5800 4100);
DISPLAY 0.872340 (-5800 4100);
DISPLAY INVISIBLE (-5800 4100);
FORCEPROP 1 LAST PATH I99
J 0
(-6127 4225);
DISPLAY 0.872340 (-6127 4225);
PAINT GREEN (-6127 4225);
DISPLAY INVISIBLE (-6127 4225);
FORCEADD QUANTA_TITLE_BLOCK_C..1
(-100 100);
FORCEPROP 0 LAST CDS_CON_LAST_MODIFIED Thu Sep 14 16:12:11 2023
J 0
(-1985 115);
DISPLAY INVISIBLE (-1985 115);
FORCEPROP 1 LAST CUSTOM_TXT_CDS <CON_LAST_MODIFIED>
J 0
(-1985 115);
DISPLAY 0.978723 (-1985 115);
FORCEPROP 2 LAST CUSTOM_TXT_CDS <XR_PAGE_TITLE>
J 0
(-7990 5350);
DISPLAY 0.638298 (-7990 5350);
PAINT PINK (-7990 5350);
DISPLAY INVISIBLE (-7990 5350);
FORCEPROP 1 LAST CUSTOM_TXT_CDS <NAME_2>
J 0
(-3275 150);
FORCEPROP 1 LAST CUSTOM_TXT_CDS <NAME_1>
J 0
(-3275 275);
FORCEPROP 1 LAST CUSTOM_TXT_CDS <Q_NUMBER>
J 0
(-1503 203);
DISPLAY 1.212766 (-1503 203);
FORCEPROP 1 LAST CUSTOM_TXT_CDS <Q_PROJ>
J 0
(-2482 202);
DISPLAY 1.212766 (-2482 202);
FORCEPROP 1 LAST CUSTOM_TXT_CDS <Q_REV>
J 0
(-284 203);
DISPLAY 1.212766 (-284 203);
FORCEPROP 1 LAST CUSTOM_TXT_CDS <CON_PAGE_NUM> OF <CON_TOTAL_PAGES>
J 0
(-546 118);
DISPLAY 0.978723 (-546 118);
FORCEPROP 1 LAST Q_TITLE DDR5 - CPU1 CHF
J 0
(-9425 150);
DISPLAY 2.446809 (-9425 150);
PAINT GREEN (-9425 150);
FORCEPROP 2 LAST PAGE_BORDER TRUE
J 0
(-7990 5350);
DISPLAY 0.638298 (-7990 5350);
PAINT PINK (-7990 5350);
DISPLAY INVISIBLE (-7990 5350);
FORCEPROP 2 LAST CDS_LIB pure_quanta
J 0
(-100 100);
DISPLAY INVISIBLE (-100 100);
FORCEPROP 1 LAST CDS_LMAN_SYM_OUTLINE -9475,6775,100,-125
J 0
(-100 100);
DISPLAY 0.468085 (-100 100);
PAINT GREEN (-100 100);
DISPLAY INVISIBLE (-100 100);
FORCEPROP 2 LAST CDS_XR_PAGE_TITLE CR-103 : @T6G_MB_LIB.T6G(SCH_1):PAGE103
J 0
(-7990 5350);
DISPLAY 0.638298 (-7990 5350);
PAINT PINK (-7990 5350);
DISPLAY INVISIBLE (-7990 5350);
FORCEPROP 1 LAST Q_DEPT BU9
J 1
(-3863 149);
DISPLAY 1.957447 (-3863 149);
PAINT GREEN (-3863 149);
DISPLAY INVISIBLE (-3863 149);
FORCEPROP 1 LAST COMMENT_BODY TRUE
J 0
(-88 87);
DISPLAY 0.978723 (-88 87);
PAINT GREEN (-88 87);
DISPLAY INVISIBLE (-88 87);
FORCEADD DNS..2
(-8450 2425);
PAINT RED (-8450 2425);
FORCEPROP 2 LAST CDS_LIB mstr_misc
J 0
(-8450 2425);
DISPLAY INVISIBLE (-8450 2425);
FORCEPROP 1 LAST COMMENT_BODY TRUE
R 1
J 0
(-8375 2200);
DISPLAY 0.872340 (-8375 2200);
PAINT PEACH (-8375 2200);
DISPLAY INVISIBLE (-8375 2200);
WIRE 17 -1 (-6075 5575)(-6075 5550);
WIRE 17 -1 (-6075 5575)(-5425 5575);
FORCEPROP 2 LAST SIG_NAME M_F_CPU1_SA_DQ<31:0>
J 0
(-6010 5585);
DISPLAY 0.489362 (-6010 5585);
WIRE 17 -1 (-7875 4150)(-7875 4175);
WIRE 17 -1 (-7875 4150)(-7875 4100);
WIRE 17 -1 (-7875 4175)(-8375 4175);
FORCEPROP 2 LAST SIG_NAME M_F_CPU1_SA_CB<7:0>
J 0
(-8325 4185);
DISPLAY 0.489362 (-8325 4185);
WIRE 17 -1 (-7875 4050)(-7875 4000);
WIRE 17 -1 (-7875 4050)(-7875 4100);
WIRE 17 -1 (-7875 3950)(-7875 4000);
WIRE 17 -1 (-7875 3900)(-7875 3950);
WIRE 17 -1 (-7875 3850)(-7875 3900);
WIRE 17 -1 (-7875 3800)(-7875 3850);
WIRE 17 -1 (-7875 3700)(-7875 3725);
WIRE 17 -1 (-7875 3700)(-7875 3650);
WIRE 17 -1 (-7875 3725)(-8375 3725);
FORCEPROP 2 LAST SIG_NAME M_F_CPU1_SB_CB<7:0>
J 0
(-8325 3735);
DISPLAY 0.489362 (-8325 3735);
WIRE 17 -1 (-7875 5250)(-7875 5300);
WIRE 17 -1 (-7875 5300)(-7875 5350);
WIRE 17 -1 (-7875 5350)(-7875 5400);
WIRE 17 -1 (-7875 5400)(-7875 5450);
WIRE 17 -1 (-7875 5450)(-7875 5500);
WIRE 17 -1 (-7875 5500)(-7875 5550);
WIRE 17 -1 (-7875 5550)(-7875 5575);
WIRE 17 -1 (-7875 5575)(-8375 5575);
FORCEPROP 2 LAST SIG_NAME M_F_CPU1_SA_CA<6:0>
J 0
(-8360 5585);
DISPLAY 0.489362 (-8360 5585);
WIRE 17 -1 (-7875 4850)(-7875 4900);
WIRE 17 -1 (-7875 4900)(-7875 4950);
WIRE 17 -1 (-7875 4950)(-7875 5000);
WIRE 17 -1 (-7875 5000)(-7875 5050);
WIRE 17 -1 (-7875 5050)(-7875 5100);
WIRE 17 -1 (-7875 5100)(-7875 5150);
WIRE 17 -1 (-7875 5150)(-7875 5175);
WIRE 17 -1 (-7875 5175)(-8375 5175);
FORCEPROP 2 LAST SIG_NAME M_F_CPU1_SB_CA<6:0>
J 0
(-8360 5185);
DISPLAY 0.489362 (-8360 5185);
WIRE 17 -1 (-7875 3600)(-7875 3650);
WIRE 17 -1 (-7875 3600)(-7875 3550);
WIRE 17 -1 (-7875 3500)(-7875 3550);
WIRE 17 -1 (-7875 3450)(-7875 3500);
WIRE 17 -1 (-7875 3400)(-7875 3450);
WIRE 17 -1 (-7875 3350)(-7875 3400);
WIRE 17 -1 (-6075 5550)(-6075 5500);
WIRE 17 -1 (-6075 5500)(-6075 5450);
WIRE 17 -1 (-6075 5450)(-6075 5400);
WIRE 17 -1 (-6075 5400)(-6075 5350);
WIRE 17 -1 (-6075 5350)(-6075 5300);
WIRE 17 -1 (-6075 5300)(-6075 5250);
WIRE 17 -1 (-6075 5250)(-6075 5200);
WIRE 17 -1 (-6075 5200)(-6075 5150);
WIRE 17 -1 (-6075 5150)(-6075 5100);
WIRE 17 -1 (-6075 5100)(-6075 5050);
WIRE 17 -1 (-6075 5050)(-6075 5000);
WIRE 17 -1 (-6075 5000)(-6075 4950);
WIRE 17 -1 (-6075 4950)(-6075 4900);
WIRE 17 -1 (-6075 4900)(-6075 4850);
WIRE 17 -1 (-6075 4850)(-6075 4800);
WIRE 17 -1 (-6075 4750)(-6075 4800);
WIRE 17 -1 (-6075 4700)(-6075 4750);
WIRE 17 -1 (-6075 4650)(-6075 4700);
WIRE 17 -1 (-6075 4600)(-6075 4650);
WIRE 17 -1 (-6075 4600)(-6075 4550);
WIRE 17 -1 (-6075 4550)(-6075 4500);
WIRE 17 -1 (-6075 4500)(-6075 4450);
WIRE 17 -1 (-6075 4450)(-6075 4400);
WIRE 17 -1 (-6075 4400)(-6075 4350);
WIRE 17 -1 (-6075 4350)(-6075 4300);
WIRE 17 -1 (-6075 4300)(-6075 4250);
WIRE 17 -1 (-6075 4250)(-6075 4200);
WIRE 17 -1 (-6075 4150)(-6075 4200);
WIRE 17 -1 (-6075 4100)(-6075 4150);
WIRE 17 -1 (-6075 4050)(-6075 4100);
WIRE 17 -1 (-6075 4000)(-6075 4050);
WIRE 17 -1 (-6075 3925)(-6075 3900);
WIRE 17 -1 (-6075 3925)(-5425 3925);
FORCEPROP 2 LAST SIG_NAME M_F_CPU1_SB_DQ<31:0>
J 0
(-6010 3935);
DISPLAY 0.489362 (-6010 3935);
WIRE 17 -1 (-6075 3900)(-6075 3850);
WIRE 17 -1 (-6075 3850)(-6075 3800);
WIRE 17 -1 (-6075 3800)(-6075 3750);
WIRE 17 -1 (-6075 3750)(-6075 3700);
WIRE 17 -1 (-6075 3700)(-6075 3650);
WIRE 17 -1 (-6075 3650)(-6075 3600);
WIRE 17 -1 (-6075 3600)(-6075 3550);
WIRE 17 -1 (-6075 3550)(-6075 3500);
WIRE 17 -1 (-6075 3500)(-6075 3450);
WIRE 17 -1 (-6075 3450)(-6075 3400);
WIRE 17 -1 (-6075 3400)(-6075 3350);
WIRE 17 -1 (-6075 3350)(-6075 3300);
WIRE 17 -1 (-6075 3300)(-6075 3250);
WIRE 17 -1 (-6075 3250)(-6075 3200);
WIRE 17 -1 (-6075 3200)(-6075 3150);
WIRE 17 -1 (-6075 3100)(-6075 3150);
WIRE 17 -1 (-6075 3050)(-6075 3100);
WIRE 17 -1 (-6075 3000)(-6075 3050);
WIRE 17 -1 (-6075 2950)(-6075 3000);
WIRE 17 -1 (-6075 2950)(-6075 2900);
WIRE 17 -1 (-6075 2900)(-6075 2850);
WIRE 17 -1 (-6075 2850)(-6075 2800);
WIRE 17 -1 (-6075 2800)(-6075 2750);
WIRE 17 -1 (-6075 2750)(-6075 2700);
WIRE 17 -1 (-6075 2700)(-6075 2650);
WIRE 17 -1 (-6075 2650)(-6075 2600);
WIRE 17 -1 (-6075 2600)(-6075 2550);
WIRE 17 -1 (-6075 2500)(-6075 2550);
WIRE 17 -1 (-6075 2450)(-6075 2500);
WIRE 17 -1 (-6075 2400)(-6075 2450);
WIRE 17 -1 (-6075 2350)(-6075 2400);
WIRE 17 -1 (-3250 4575)(-3250 4475);
WIRE 17 -1 (-3250 4675)(-3250 4575);
WIRE 17 -1 (-3250 4475)(-3250 4375);
WIRE 17 -1 (-3250 4375)(-3250 4275);
WIRE 17 -1 (-3250 4700)(-3250 4675);
WIRE 17 -1 (-3250 4700)(-2550 4700);
FORCEPROP 2 LAST SIG_NAME M_F_CPU1_SA_DQS_DN<9:0>
J 0
(-3185 4710);
DISPLAY 0.489362 (-3185 4710);
WIRE 17 -1 (-3450 4525)(-3450 4425);
WIRE 17 -1 (-3450 4625)(-3450 4525);
WIRE 17 -1 (-3450 4425)(-3450 4325);
WIRE 17 -1 (-3450 4225)(-3450 4325);
WIRE 17 -1 (-3450 4725)(-3450 4625);
WIRE 17 -1 (-3450 4750)(-3450 4725);
WIRE 17 -1 (-3450 4125)(-3450 4225);
WIRE 17 -1 (-3450 4025)(-3450 4125);
WIRE 17 -1 (-3450 4750)(-2550 4750);
FORCEPROP 2 LAST SIG_NAME M_F_CPU1_SA_DQS_DP<9:0>
J 0
(-3185 4760);
DISPLAY 0.489362 (-3185 4760);
WIRE 17 -1 (-3450 3675)(-3450 3575);
WIRE 17 -1 (-3450 3700)(-3450 3675);
WIRE 17 -1 (-3450 3575)(-3450 3475);
WIRE 17 -1 (-3450 3475)(-3450 3375);
WIRE 17 -1 (-3450 3700)(-2550 3700);
FORCEPROP 2 LAST SIG_NAME M_F_CPU1_SB_DQS_DP<9:0>
J 0
(-3185 3710);
DISPLAY 0.489362 (-3185 3710);
WIRE 17 -1 (-3250 3625)(-3250 3525);
WIRE 17 -1 (-3250 3650)(-3250 3625);
WIRE 17 -1 (-3250 3525)(-3250 3425);
WIRE 17 -1 (-3250 3425)(-3250 3325);
WIRE 17 -1 (-3250 3650)(-2550 3650);
FORCEPROP 2 LAST SIG_NAME M_F_CPU1_SB_DQS_DN<9:0>
J 0
(-3185 3660);
DISPLAY 0.489362 (-3185 3660);
WIRE 17 -1 (-3450 3375)(-3450 3275);
WIRE 17 -1 (-3250 3875)(-3250 3775);
WIRE 17 -1 (-3250 3975)(-3250 3875);
WIRE 17 -1 (-3250 3975)(-3250 4075);
WIRE 17 -1 (-3250 4075)(-3250 4175);
WIRE 17 -1 (-3250 4175)(-3250 4275);
WIRE 17 -1 (-3450 3925)(-3450 3825);
WIRE 17 -1 (-3450 4025)(-3450 3925);
WIRE 17 -1 (-3250 2825)(-3250 2725);
WIRE 17 -1 (-3250 2925)(-3250 2825);
WIRE 17 -1 (-3250 2925)(-3250 3025);
WIRE 17 -1 (-3250 3025)(-3250 3125);
WIRE 17 -1 (-3250 3125)(-3250 3225);
WIRE 17 -1 (-3250 3325)(-3250 3225);
WIRE 17 -1 (-3450 2875)(-3450 2775);
WIRE 17 -1 (-3450 2975)(-3450 2875);
WIRE 17 -1 (-3450 2975)(-3450 3075);
WIRE 17 -1 (-3450 3075)(-3450 3175);
WIRE 17 -1 (-3450 3175)(-3450 3275);
WIRE 16 -1 (-6550 1100)(-6550 1175);
WIRE 16 -1 (-8675 3175)(-8675 3250);
WIRE 16 -1 (-8475 2525)(-8475 2550);
WIRE 16 -1 (-7575 3375)(-7775 3375);
WIRE 16 -1 (-8575 3075)(-7575 3075);
WIRE 16 -1 (-8575 3475)(-8575 3075);
WIRE 16 -1 (-8575 3500)(-8575 3475);
WIRE 16 -1 (-8675 3475)(-8575 3475);
WIRE 16 -1 (-8675 3450)(-8675 3475);
WIRE 16 -1 (-7575 3025)(-8750 3025);
FORCEPROP 2 LAST SIG_NAME PD_CHF_CPU1_DIMM_SAA
J 0
(-8725 3035);
DISPLAY 0.489362 (-8725 3035);
WIRE 16 -1 (-7575 2975)(-8150 2975);
FORCEPROP 2 LAST SIG_NAME I3C_SPD_DDRF_CPU1_SDA
J 0
(-8060 2985);
DISPLAY 0.446809 (-8060 2985);
FORCEPROP 2 LASTPROP $XRERR UNIQUE?
J 0
(-8300 2985);
DISPLAY 0.638298 (-8300 2985);
PAINT MONO (-8300 2985);
DISPLAY INVISIBLE (-8300 2985);
WIRE 16 -1 (-8375 2975)(-8350 2975);
WIRE 16 -1 (-8375 2850)(-8375 2975);
WIRE 16 -1 (-8375 2850)(-8850 2850);
FORCEPROP 2 LAST SIG_NAME I3C_SPD_DDRAF_CPU1_SDA
J 0
(-8885 2860);
DISPLAY 0.489362 (-8885 2860);
WIRE 16 -1 (-7950 2750)(-8500 2750);
FORCEPROP 2 LAST SIG_NAME I3C_SPD_DDRAF_CPU1_SCL
J 0
(-8485 2760);
DISPLAY 0.489362 (-8485 2760);
WIRE 16 -1 (-7575 2925)(-7675 2925);
FORCEPROP 2 LAST SIG_NAME I3C_SPD_DDRF_CPU1_SCL
J 0
(-8060 2935);
DISPLAY 0.446809 (-8060 2935);
FORCEPROP 2 LASTPROP $XRERR UNIQUE?
J 0
(-8300 2935);
DISPLAY 0.638298 (-8300 2935);
PAINT MONO (-8300 2935);
DISPLAY INVISIBLE (-8300 2935);
WIRE 16 -1 (-7675 2925)(-7675 2750);
WIRE 16 -1 (-7675 2750)(-7750 2750);
WIRE 16 -1 (-1900 2225)(-2200 2225);
WIRE 16 -1 (-2200 2275)(-2200 2225);
WIRE 16 -1 (-2200 2225)(-2200 2175);
WIRE 16 -1 (-1900 2175)(-2200 2175);
WIRE 16 -1 (-2200 2175)(-2200 2050);
WIRE 16 -1 (-1900 2275)(-2200 2275);
WIRE 16 -1 (-2200 2325)(-2200 2275);
WIRE 16 -1 (-1900 2325)(-2200 2325);
WIRE 16 -1 (-2200 2375)(-2200 2325);
WIRE 16 -1 (-1900 2375)(-2200 2375);
WIRE 16 -1 (-2200 2425)(-2200 2375);
WIRE 16 -1 (-1900 2425)(-2200 2425);
WIRE 16 -1 (-2200 2475)(-2200 2425);
WIRE 16 -1 (-1900 2475)(-2200 2475);
WIRE 16 -1 (-2200 2525)(-2200 2475);
WIRE 16 -1 (-1900 2525)(-2200 2525);
WIRE 16 -1 (-2200 2575)(-2200 2525);
WIRE 16 -1 (-1900 2575)(-2200 2575);
WIRE 16 -1 (-2200 2625)(-2200 2575);
WIRE 16 -1 (-1900 2625)(-2200 2625);
WIRE 16 -1 (-2200 2675)(-2200 2625);
WIRE 16 -1 (-1900 2675)(-2200 2675);
WIRE 16 -1 (-2200 2725)(-2200 2675);
WIRE 16 -1 (-1900 2725)(-2200 2725);
WIRE 16 -1 (-2200 2775)(-2200 2725);
WIRE 16 -1 (-1900 2775)(-2200 2775);
WIRE 16 -1 (-2200 2825)(-2200 2775);
WIRE 16 -1 (-1900 2825)(-2200 2825);
WIRE 16 -1 (-2200 2875)(-2200 2825);
WIRE 16 -1 (-1900 2875)(-2200 2875);
WIRE 16 -1 (-2200 2925)(-2200 2875);
WIRE 16 -1 (-1900 2925)(-2200 2925);
WIRE 16 -1 (-2200 2975)(-2200 2925);
WIRE 16 -1 (-1900 2975)(-2200 2975);
WIRE 16 -1 (-2200 3025)(-2200 2975);
WIRE 16 -1 (-1900 3025)(-2200 3025);
WIRE 16 -1 (-2200 3075)(-2200 3025);
WIRE 16 -1 (-1900 3075)(-2200 3075);
WIRE 16 -1 (-2200 3125)(-2200 3075);
WIRE 16 -1 (-1900 3125)(-2200 3125);
WIRE 16 -1 (-2200 3175)(-2200 3125);
WIRE 16 -1 (-1900 3175)(-2200 3175);
WIRE 16 -1 (-2200 3225)(-2200 3175);
WIRE 16 -1 (-1900 3225)(-2200 3225);
WIRE 16 -1 (-2200 3275)(-2200 3225);
WIRE 16 -1 (-1900 3275)(-2200 3275);
WIRE 16 -1 (-2200 3325)(-2200 3275);
WIRE 16 -1 (-1900 3325)(-2200 3325);
WIRE 16 -1 (-2200 3375)(-2200 3325);
WIRE 16 -1 (-1900 3375)(-2200 3375);
WIRE 16 -1 (-2200 3425)(-2200 3375);
WIRE 16 -1 (-1900 3425)(-2200 3425);
WIRE 16 -1 (-2200 3475)(-2200 3425);
WIRE 16 -1 (-1900 3475)(-2200 3475);
WIRE 16 -1 (-2200 3525)(-2200 3475);
WIRE 16 -1 (-1900 3525)(-2200 3525);
WIRE 16 -1 (-2200 3575)(-2200 3525);
WIRE 16 -1 (-1900 3575)(-2200 3575);
WIRE 16 -1 (-2200 3625)(-2200 3575);
WIRE 16 -1 (-1900 3625)(-2200 3625);
WIRE 16 -1 (-2200 3675)(-2200 3625);
WIRE 16 -1 (-1900 3675)(-2200 3675);
WIRE 16 -1 (-2200 3725)(-2200 3675);
WIRE 16 -1 (-1900 3725)(-2200 3725);
WIRE 16 -1 (-2200 3775)(-2200 3725);
WIRE 16 -1 (-1900 3775)(-2200 3775);
WIRE 16 -1 (-2200 3825)(-2200 3775);
WIRE 16 -1 (-1900 3825)(-2200 3825);
WIRE 16 -1 (-2200 3875)(-2200 3825);
WIRE 16 -1 (-1900 3875)(-2200 3875);
WIRE 16 -1 (-2200 3925)(-2200 3875);
WIRE 16 -1 (-1900 3925)(-2200 3925);
WIRE 16 -1 (-2200 3975)(-2200 3925);
WIRE 16 -1 (-1900 3975)(-2200 3975);
WIRE 16 -1 (-2200 4025)(-2200 3975);
WIRE 16 -1 (-1900 4025)(-2200 4025);
WIRE 16 -1 (-2200 4075)(-2200 4025);
WIRE 16 -1 (-2200 4125)(-2200 4075);
WIRE 16 -1 (-1900 4075)(-2200 4075);
WIRE 16 -1 (-1900 4125)(-2200 4125);
WIRE 16 -1 (-2200 4175)(-2200 4125);
WIRE 16 -1 (-1900 4175)(-2200 4175);
WIRE 16 -1 (-2200 4225)(-2200 4175);
WIRE 16 -1 (-1900 4225)(-2200 4225);
WIRE 16 -1 (-2200 4275)(-2200 4225);
WIRE 16 -1 (-1900 4275)(-2200 4275);
WIRE 16 -1 (-2200 4325)(-2200 4275);
WIRE 16 -1 (-1900 4325)(-2200 4325);
WIRE 16 -1 (-2200 4375)(-2200 4325);
WIRE 16 -1 (-1900 4375)(-2200 4375);
WIRE 16 -1 (-2200 4425)(-2200 4375);
WIRE 16 -1 (-1900 4425)(-2200 4425);
WIRE 16 -1 (-2200 4475)(-2200 4425);
WIRE 16 -1 (-1900 4475)(-2200 4475);
WIRE 16 -1 (-2200 4525)(-2200 4475);
WIRE 16 -1 (-1900 4525)(-2200 4525);
WIRE 16 -1 (-2200 4575)(-2200 4525);
WIRE 16 -1 (-1900 4575)(-2200 4575);
WIRE 16 -1 (-2200 4625)(-2200 4575);
WIRE 16 -1 (-1900 4625)(-2200 4625);
WIRE 16 -1 (-2200 4675)(-2200 4625);
WIRE 16 -1 (-1900 4675)(-2200 4675);
WIRE 16 -1 (-2200 4725)(-2200 4675);
WIRE 16 -1 (-1900 4725)(-2200 4725);
WIRE 16 -1 (-2200 4775)(-2200 4725);
WIRE 16 -1 (-1900 4775)(-2200 4775);
WIRE 16 -1 (-2200 4825)(-2200 4775);
WIRE 16 -1 (-1900 4825)(-2200 4825);
WIRE 16 -1 (-2200 4875)(-2200 4825);
WIRE 16 -1 (-1900 4875)(-2200 4875);
WIRE 16 -1 (-2200 4925)(-2200 4875);
WIRE 16 -1 (-1900 4925)(-2200 4925);
WIRE 16 -1 (-2200 4975)(-2200 4925);
WIRE 16 -1 (-1900 4975)(-2200 4975);
WIRE 16 -1 (-2200 5025)(-2200 4975);
WIRE 16 -1 (-1900 5025)(-2200 5025);
WIRE 16 -1 (-2200 5075)(-2200 5025);
WIRE 16 -1 (-1900 5075)(-2200 5075);
WIRE 16 -1 (-2200 5125)(-2200 5075);
WIRE 16 -1 (-1900 5125)(-2200 5125);
WIRE 16 -1 (-2200 5175)(-2200 5125);
WIRE 16 -1 (-1900 5175)(-2200 5175);
WIRE 16 -1 (-2200 5225)(-2200 5175);
WIRE 16 -1 (-1900 5225)(-2200 5225);
WIRE 16 -1 (-2200 5275)(-2200 5225);
WIRE 16 -1 (-1900 5275)(-2200 5275);
WIRE 16 -1 (-400 2275)(-400 2175);
WIRE 16 -1 (-400 2325)(-400 2275);
WIRE 16 -1 (-400 2275)(-700 2275);
WIRE 16 -1 (-400 2175)(-400 2125);
WIRE 16 -1 (-400 2175)(-700 2175);
WIRE 16 -1 (-400 2125)(-400 2075);
WIRE 16 -1 (-400 2125)(-700 2125);
WIRE 16 -1 (-400 2375)(-400 2325);
WIRE 16 -1 (-400 2325)(-700 2325);
WIRE 16 -1 (-400 2425)(-400 2375);
WIRE 16 -1 (-400 2375)(-700 2375);
WIRE 16 -1 (-400 2075)(-700 2075);
WIRE 16 -1 (-400 2075)(-400 1825);
WIRE 16 -1 (-400 2475)(-400 2425);
WIRE 16 -1 (-400 2425)(-700 2425);
WIRE 16 -1 (-400 2525)(-400 2475);
WIRE 16 -1 (-400 2475)(-700 2475);
WIRE 16 -1 (-400 2575)(-400 2525);
WIRE 16 -1 (-400 2525)(-700 2525);
WIRE 16 -1 (-400 2625)(-400 2575);
WIRE 16 -1 (-400 2575)(-700 2575);
WIRE 16 -1 (-400 2675)(-400 2625);
WIRE 16 -1 (-400 2625)(-700 2625);
WIRE 16 -1 (-400 2725)(-400 2675);
WIRE 16 -1 (-400 2675)(-700 2675);
WIRE 16 -1 (-400 2775)(-400 2725);
WIRE 16 -1 (-400 2725)(-700 2725);
WIRE 16 -1 (-400 2825)(-400 2775);
WIRE 16 -1 (-400 2775)(-700 2775);
WIRE 16 -1 (-400 2875)(-400 2825);
WIRE 16 -1 (-400 2825)(-700 2825);
WIRE 16 -1 (-400 2925)(-400 2875);
WIRE 16 -1 (-400 2875)(-700 2875);
WIRE 16 -1 (-400 2975)(-400 2925);
WIRE 16 -1 (-400 2925)(-700 2925);
WIRE 16 -1 (-400 3025)(-400 2975);
WIRE 16 -1 (-400 2975)(-700 2975);
WIRE 16 -1 (-400 3075)(-400 3025);
WIRE 16 -1 (-400 3025)(-700 3025);
WIRE 16 -1 (-400 3125)(-400 3075);
WIRE 16 -1 (-400 3075)(-700 3075);
WIRE 16 -1 (-400 3175)(-400 3125);
WIRE 16 -1 (-400 3125)(-700 3125);
WIRE 16 -1 (-400 3225)(-400 3175);
WIRE 16 -1 (-400 3175)(-700 3175);
WIRE 16 -1 (-400 3275)(-400 3225);
WIRE 16 -1 (-400 3225)(-700 3225);
WIRE 16 -1 (-400 3325)(-400 3275);
WIRE 16 -1 (-400 3275)(-700 3275);
WIRE 16 -1 (-400 3375)(-400 3325);
WIRE 16 -1 (-400 3325)(-700 3325);
WIRE 16 -1 (-400 3425)(-400 3375);
WIRE 16 -1 (-400 3375)(-700 3375);
WIRE 16 -1 (-400 3475)(-400 3425);
WIRE 16 -1 (-400 3425)(-700 3425);
WIRE 16 -1 (-400 3525)(-400 3475);
WIRE 16 -1 (-400 3475)(-700 3475);
WIRE 16 -1 (-400 3575)(-400 3525);
WIRE 16 -1 (-400 3525)(-700 3525);
WIRE 16 -1 (-400 3625)(-400 3575);
WIRE 16 -1 (-400 3575)(-700 3575);
WIRE 16 -1 (-400 3675)(-400 3625);
WIRE 16 -1 (-400 3625)(-700 3625);
WIRE 16 -1 (-400 3725)(-400 3675);
WIRE 16 -1 (-400 3675)(-700 3675);
WIRE 16 -1 (-400 3775)(-400 3725);
WIRE 16 -1 (-400 3725)(-700 3725);
WIRE 16 -1 (-400 3825)(-400 3775);
WIRE 16 -1 (-400 3775)(-700 3775);
WIRE 16 -1 (-400 3875)(-400 3825);
WIRE 16 -1 (-400 3825)(-700 3825);
WIRE 16 -1 (-400 3925)(-400 3875);
WIRE 16 -1 (-400 3875)(-700 3875);
WIRE 16 -1 (-400 3975)(-400 3925);
WIRE 16 -1 (-400 3925)(-700 3925);
WIRE 16 -1 (-400 4025)(-400 3975);
WIRE 16 -1 (-400 3975)(-700 3975);
WIRE 16 -1 (-400 4075)(-400 4025);
WIRE 16 -1 (-400 4025)(-700 4025);
WIRE 16 -1 (-400 4125)(-400 4075);
WIRE 16 -1 (-400 4075)(-700 4075);
WIRE 16 -1 (-400 4175)(-400 4125);
WIRE 16 -1 (-400 4125)(-700 4125);
WIRE 16 -1 (-400 4225)(-400 4175);
WIRE 16 -1 (-400 4175)(-700 4175);
WIRE 16 -1 (-400 4275)(-400 4225);
WIRE 16 -1 (-400 4225)(-700 4225);
WIRE 16 -1 (-400 4325)(-400 4275);
WIRE 16 -1 (-400 4275)(-700 4275);
WIRE 16 -1 (-400 4375)(-400 4325);
WIRE 16 -1 (-400 4325)(-700 4325);
WIRE 16 -1 (-400 4425)(-400 4375);
WIRE 16 -1 (-400 4375)(-700 4375);
WIRE 16 -1 (-400 4475)(-400 4425);
WIRE 16 -1 (-400 4425)(-700 4425);
WIRE 16 -1 (-400 4525)(-400 4475);
WIRE 16 -1 (-400 4475)(-700 4475);
WIRE 16 -1 (-400 4575)(-400 4525);
WIRE 16 -1 (-400 4525)(-700 4525);
WIRE 16 -1 (-400 4625)(-400 4575);
WIRE 16 -1 (-400 4575)(-700 4575);
WIRE 16 -1 (-400 4675)(-400 4625);
WIRE 16 -1 (-400 4625)(-700 4625);
WIRE 16 -1 (-400 4725)(-400 4675);
WIRE 16 -1 (-400 4675)(-700 4675);
WIRE 16 -1 (-400 4775)(-400 4725);
WIRE 16 -1 (-400 4725)(-700 4725);
WIRE 16 -1 (-400 4825)(-400 4775);
WIRE 16 -1 (-400 4775)(-700 4775);
WIRE 16 -1 (-400 4875)(-400 4825);
WIRE 16 -1 (-400 4825)(-700 4825);
WIRE 16 -1 (-400 4925)(-400 4875);
WIRE 16 -1 (-400 4875)(-700 4875);
WIRE 16 -1 (-400 4975)(-400 4925);
WIRE 16 -1 (-400 4925)(-700 4925);
WIRE 16 -1 (-400 5025)(-400 4975);
WIRE 16 -1 (-400 4975)(-700 4975);
WIRE 16 -1 (-400 5075)(-400 5025);
WIRE 16 -1 (-400 5025)(-700 5025);
WIRE 16 -1 (-400 5125)(-400 5075);
WIRE 16 -1 (-400 5075)(-700 5075);
WIRE 16 -1 (-400 5175)(-400 5125);
WIRE 16 -1 (-400 5125)(-700 5125);
WIRE 16 -1 (-400 5225)(-400 5175);
WIRE 16 -1 (-400 5175)(-700 5175);
WIRE 16 -1 (-400 5275)(-400 5225);
WIRE 16 -1 (-400 5225)(-700 5225);
WIRE 16 -1 (-400 5325)(-400 5275);
WIRE 16 -1 (-400 5275)(-700 5275);
WIRE 16 -1 (-400 5375)(-400 5325);
WIRE 16 -1 (-400 5325)(-700 5325);
WIRE 16 -1 (-400 5425)(-400 5375);
WIRE 16 -1 (-400 5375)(-700 5375);
WIRE 16 -1 (-400 5425)(-700 5425);
WIRE 16 -1 (-2325 5775)(-2325 5900);
WIRE 16 -1 (-2325 5775)(-2900 5775);
WIRE 16 -1 (-2900 5775)(-2900 5900);
WIRE 16 -1 (-2900 5775)(-2900 5700);
WIRE 16 -1 (-2325 6200)(-2200 6200);
WIRE 16 -1 (-2325 6200)(-2900 6200);
WIRE 16 -1 (-2325 6200)(-2325 6100);
WIRE 16 -1 (-2200 5425)(-2200 6200);
WIRE 16 -1 (-1900 5425)(-2200 5425);
WIRE 16 -1 (-2200 5375)(-2200 5425);
WIRE 16 -1 (-2900 6100)(-2900 6200);
WIRE 16 -1 (-2900 6200)(-2900 6275);
WIRE 16 -1 (-1900 5375)(-2200 5375);
WIRE 16 -1 (-2200 5375)(-2200 5325);
WIRE 16 -1 (-2200 5325)(-1900 5325);
WIRE 16 -1 (-8275 2275)(-8275 2675);
WIRE 16 -1 (-8275 2275)(-8475 2275);
WIRE 16 -1 (-7575 2675)(-8275 2675);
FORCEPROP 2 LAST SIG_NAME PWRGD_CHF_CPU1_DIMM
J 0
(-8150 2685);
DISPLAY 0.489362 (-8150 2685);
FORCEPROP 2 LASTPROP $XRERR UNIQUE?
J 0
(-8390 2685);
DISPLAY 0.638298 (-8390 2685);
PAINT MONO (-8390 2685);
DISPLAY INVISIBLE (-8390 2685);
WIRE 16 -1 (-8475 2325)(-8475 2275);
WIRE 16 -1 (-8475 2275)(-8500 2275);
WIRE 16 -1 (-7575 3175)(-8175 3175);
FORCEPROP 2 LAST SIG_NAME M_F_CPU1_ALERT_N
J 0
(-8160 3185);
DISPLAY 0.489362 (-8160 3185);
WIRE 16 -1 (-7575 3225)(-8175 3225);
FORCEPROP 2 LAST SIG_NAME M_F_CPU1_RESET_N
J 0
(-8160 3235);
DISPLAY 0.489362 (-8160 3235);
WIRE 16 -1 (-7575 3325)(-7775 3325);
WIRE 16 -1 (-9050 2275)(-8700 2275);
FORCEPROP 2 LAST SIG_NAME PWRGD_CHAF_CPU1
J 0
(-9035 2285);
DISPLAY 0.489362 (-9035 2285);
WIRE 16 -1 (-7575 2075)(-8375 2075);
FORCEPROP 2 LAST SIG_NAME M_F_CPU1_SB_RSP<0>
J 0
(-8325 2085);
DISPLAY 0.489362 (-8325 2085);
WIRE 16 -1 (-7575 2125)(-8375 2125);
FORCEPROP 2 LAST SIG_NAME M_F_CPU1_SA_RSP<0>
J 0
(-8325 2135);
DISPLAY 0.489362 (-8325 2135);
WIRE 16 -1 (-6175 4675)(-6375 4675);
WIRE 16 -1 (-6175 4625)(-6375 4625);
WIRE 16 -1 (-6175 4575)(-6375 4575);
WIRE 16 -1 (-6375 4525)(-6175 4525);
WIRE 16 -1 (-6175 4475)(-6375 4475);
WIRE 16 -1 (-6175 4975)(-6375 4975);
WIRE 16 -1 (-6375 4925)(-6175 4925);
WIRE 16 -1 (-6175 4875)(-6375 4875);
WIRE 16 -1 (-3700 3650)(-3550 3650);
WIRE 16 -1 (-3700 3600)(-3350 3600);
WIRE 16 -1 (-3700 4700)(-3550 4700);
WIRE 16 -1 (-3700 4650)(-3350 4650);
WIRE 16 -1 (-3550 4600)(-3700 4600);
WIRE 16 -1 (-3700 4550)(-3350 4550);
WIRE 16 -1 (-3700 3400)(-3350 3400);
WIRE 16 -1 (-3550 4500)(-3700 4500);
WIRE 16 -1 (-3550 3350)(-3700 3350);
WIRE 16 -1 (-3700 3300)(-3350 3300);
WIRE 16 -1 (-3350 4350)(-3700 4350);
WIRE 16 -1 (-3700 3250)(-3550 3250);
WIRE 16 -1 (-3700 3200)(-3350 3200);
WIRE 16 -1 (-3700 4300)(-3550 4300);
WIRE 16 -1 (-3350 4250)(-3700 4250);
WIRE 16 -1 (-3550 3150)(-3700 3150);
WIRE 16 -1 (-3700 3100)(-3350 3100);
WIRE 16 -1 (-3550 4200)(-3700 4200);
WIRE 16 -1 (-3700 4150)(-3350 4150);
WIRE 16 -1 (-3550 3050)(-3700 3050);
WIRE 16 -1 (-3700 3000)(-3350 3000);
WIRE 16 -1 (-3550 4100)(-3700 4100);
WIRE 16 -1 (-3700 4050)(-3350 4050);
WIRE 16 -1 (-3550 2950)(-3700 2950);
WIRE 16 -1 (-3700 2900)(-3350 2900);
WIRE 16 -1 (-3550 4000)(-3700 4000);
WIRE 16 -1 (-3700 3950)(-3350 3950);
WIRE 16 -1 (-3700 2850)(-3550 2850);
WIRE 16 -1 (-3700 2800)(-3350 2800);
WIRE 16 -1 (-3700 3900)(-3550 3900);
WIRE 16 -1 (-3700 3850)(-3350 3850);
WIRE 16 -1 (-3550 2750)(-3700 2750);
WIRE 16 -1 (-3700 2700)(-3350 2700);
WIRE 16 -1 (-3550 3800)(-3700 3800);
WIRE 16 -1 (-3700 3750)(-3350 3750);
WIRE 16 -1 (-3550 3450)(-3700 3450);
WIRE 16 -1 (-3700 3500)(-3350 3500);
WIRE 16 -1 (-3550 3550)(-3700 3550);
WIRE 16 -1 (-3550 4400)(-3700 4400);
WIRE 16 -1 (-3700 4450)(-3350 4450);
WIRE 16 -1 (-7575 4675)(-8375 4675);
FORCEPROP 2 LAST SIG_NAME M_F_CPU1_SB_PAR
J 0
(-8325 4685);
DISPLAY 0.489362 (-8325 4685);
WIRE 16 -1 (-7575 4725)(-8375 4725);
FORCEPROP 2 LAST SIG_NAME M_F_CPU1_SA_PAR
J 0
(-8325 4735);
DISPLAY 0.489362 (-8325 4735);
WIRE 16 -1 (-6175 2325)(-6375 2325);
WIRE 16 -1 (-6175 2375)(-6375 2375);
WIRE 16 -1 (-6175 2425)(-6375 2425);
WIRE 16 -1 (-6375 2475)(-6175 2475);
WIRE 16 -1 (-6175 2525)(-6375 2525);
WIRE 16 -1 (-6175 2575)(-6375 2575);
WIRE 16 -1 (-6175 2625)(-6375 2625);
WIRE 16 -1 (-6375 2675)(-6175 2675);
WIRE 16 -1 (-6175 2725)(-6375 2725);
WIRE 16 -1 (-6175 2775)(-6375 2775);
WIRE 16 -1 (-6175 2825)(-6375 2825);
WIRE 16 -1 (-6375 2875)(-6175 2875);
WIRE 16 -1 (-6175 2925)(-6375 2925);
WIRE 16 -1 (-6175 2975)(-6375 2975);
WIRE 16 -1 (-6175 3025)(-6375 3025);
WIRE 16 -1 (-6375 3075)(-6175 3075);
WIRE 16 -1 (-6175 3125)(-6375 3125);
WIRE 16 -1 (-6175 3175)(-6375 3175);
WIRE 16 -1 (-6175 3225)(-6375 3225);
WIRE 16 -1 (-6375 3275)(-6175 3275);
WIRE 16 -1 (-6175 3325)(-6375 3325);
WIRE 16 -1 (-6175 3375)(-6375 3375);
WIRE 16 -1 (-6175 3425)(-6375 3425);
WIRE 16 -1 (-6375 3475)(-6175 3475);
WIRE 16 -1 (-6175 3525)(-6375 3525);
WIRE 16 -1 (-6175 3575)(-6375 3575);
WIRE 16 -1 (-6175 3625)(-6375 3625);
WIRE 16 -1 (-6375 3675)(-6175 3675);
WIRE 16 -1 (-6175 3725)(-6375 3725);
WIRE 16 -1 (-6175 3775)(-6375 3775);
WIRE 16 -1 (-6175 3825)(-6375 3825);
WIRE 16 -1 (-6375 3875)(-6175 3875);
WIRE 16 -1 (-6175 3975)(-6375 3975);
WIRE 16 -1 (-6175 4025)(-6375 4025);
WIRE 16 -1 (-6175 4075)(-6375 4075);
WIRE 16 -1 (-6375 4125)(-6175 4125);
WIRE 16 -1 (-6175 4175)(-6375 4175);
WIRE 16 -1 (-6175 4225)(-6375 4225);
WIRE 16 -1 (-6175 4275)(-6375 4275);
WIRE 16 -1 (-6375 4325)(-6175 4325);
WIRE 16 -1 (-6175 4375)(-6375 4375);
WIRE 16 -1 (-6175 4425)(-6375 4425);
WIRE 16 -1 (-6375 4725)(-6175 4725);
WIRE 16 -1 (-6175 4775)(-6375 4775);
WIRE 16 -1 (-6175 4825)(-6375 4825);
WIRE 16 -1 (-6175 5025)(-6375 5025);
WIRE 16 -1 (-6175 5075)(-6375 5075);
WIRE 16 -1 (-6375 5125)(-6175 5125);
WIRE 16 -1 (-6175 5175)(-6375 5175);
WIRE 16 -1 (-6175 5225)(-6375 5225);
WIRE 16 -1 (-6175 5275)(-6375 5275);
WIRE 16 -1 (-6375 5325)(-6175 5325);
WIRE 16 -1 (-6175 5375)(-6375 5375);
WIRE 16 -1 (-6175 5425)(-6375 5425);
WIRE 16 -1 (-6175 5475)(-6375 5475);
WIRE 16 -1 (-7575 4425)(-8375 4425);
FORCEPROP 2 LAST SIG_NAME M_F_CPU1_SB_CS_N<1>
J 0
(-8325 4435);
DISPLAY 0.489362 (-8325 4435);
WIRE 16 -1 (-7575 4575)(-8375 4575);
FORCEPROP 2 LAST SIG_NAME M_F_CPU1_SA_CS_N<1>
J 0
(-8325 4585);
DISPLAY 0.489362 (-8325 4585);
WIRE 16 -1 (-7575 4375)(-8375 4375);
FORCEPROP 2 LAST SIG_NAME M_F_CPU1_SB_CS_N<0>
J 0
(-8325 4385);
DISPLAY 0.489362 (-8325 4385);
WIRE 16 -1 (-7575 4525)(-8375 4525);
FORCEPROP 2 LAST SIG_NAME M_F_CPU1_SA_CS_N<0>
J 0
(-8325 4535);
DISPLAY 0.489362 (-8325 4535);
WIRE 16 -1 (-7575 4275)(-8375 4275);
FORCEPROP 2 LAST SIG_NAME M_F_CPU1_CLK_DP<0>
J 0
(-8325 4285);
DISPLAY 0.489362 (-8325 4285);
WIRE 16 -1 (-7575 4225)(-8375 4225);
FORCEPROP 2 LAST SIG_NAME M_F_CPU1_CLK_DN<0>
J 0
(-8325 4235);
DISPLAY 0.489362 (-8325 4235);
WIRE 16 -1 (-7575 3425)(-7775 3425);
WIRE 16 -1 (-7575 3475)(-7775 3475);
WIRE 16 -1 (-7575 3525)(-7775 3525);
WIRE 16 -1 (-7575 3575)(-7775 3575);
WIRE 16 -1 (-7575 3625)(-7775 3625);
WIRE 16 -1 (-7575 3775)(-7775 3775);
WIRE 16 -1 (-7575 3875)(-7775 3875);
WIRE 16 -1 (-7575 3925)(-7775 3925);
WIRE 16 -1 (-7575 4025)(-7775 4025);
WIRE 16 -1 (-7575 4075)(-7775 4075);
WIRE 16 -1 (-7575 5125)(-7775 5125);
WIRE 16 -1 (-7575 5525)(-7775 5525);
WIRE 16 -1 (-7575 5075)(-7775 5075);
WIRE 16 -1 (-7575 5475)(-7775 5475);
WIRE 16 -1 (-7575 5025)(-7775 5025);
WIRE 16 -1 (-7575 5425)(-7775 5425);
WIRE 16 -1 (-7575 4975)(-7775 4975);
WIRE 16 -1 (-7575 5375)(-7775 5375);
WIRE 16 -1 (-7575 4925)(-7775 4925);
WIRE 16 -1 (-7575 5325)(-7775 5325);
WIRE 16 -1 (-7575 4875)(-7775 4875);
WIRE 16 -1 (-7575 5275)(-7775 5275);
WIRE 16 -1 (-7575 4825)(-7775 4825);
WIRE 16 -1 (-7575 5225)(-7775 5225);
WIRE 16 -1 (-7575 3675)(-7775 3675);
WIRE 16 -1 (-7575 3825)(-7775 3825);
WIRE 16 -1 (-7575 3975)(-7775 3975);
WIRE 16 -1 (-7575 4125)(-7775 4125);
WIRE 16 -1 (-6375 5525)(-6175 5525);
WIRE 16 -1 (-6550 1450)(-6550 1375);
WIRE 16 -1 (-6550 1450)(-7275 1450);
FORCEPROP 2 LAST SIG_NAME PD_CHF_CPU1_DIMM_SAA
J 0
(-7260 1460);
DISPLAY 0.489362 (-7260 1460);
DOT 1 (-8575 3475);
DOT 1 (-2200 5225);
DOT 1 (-2200 5425);
DOT 1 (-2200 4425);
DOT 1 (-400 5375);
DOT 1 (-400 5325);
DOT 1 (-400 5275);
DOT 1 (-400 5225);
DOT 1 (-400 5175);
DOT 1 (-400 5125);
DOT 1 (-400 5075);
DOT 1 (-400 5025);
DOT 1 (-400 4975);
DOT 1 (-400 4925);
DOT 1 (-400 4875);
DOT 1 (-400 4825);
DOT 1 (-400 4775);
DOT 1 (-400 4725);
DOT 1 (-400 4675);
DOT 1 (-400 4625);
DOT 1 (-400 4575);
DOT 1 (-400 4525);
DOT 1 (-400 4475);
DOT 1 (-400 4425);
DOT 1 (-400 4375);
DOT 1 (-400 4325);
DOT 1 (-400 4275);
DOT 1 (-400 4225);
DOT 1 (-400 4175);
DOT 1 (-400 4125);
DOT 1 (-400 4075);
DOT 1 (-400 4025);
DOT 1 (-400 3975);
DOT 1 (-2200 5375);
DOT 1 (-2200 5175);
DOT 1 (-2200 5125);
DOT 1 (-2200 5075);
DOT 1 (-2200 5025);
DOT 1 (-2200 4975);
DOT 1 (-2200 4925);
DOT 1 (-2200 4875);
DOT 1 (-2200 4825);
DOT 1 (-2200 4775);
DOT 1 (-2200 4725);
DOT 1 (-2200 4675);
DOT 1 (-2200 4625);
DOT 1 (-2200 4575);
DOT 1 (-2200 4525);
DOT 1 (-2200 4475);
DOT 1 (-2200 4375);
DOT 1 (-2200 4325);
DOT 1 (-2200 4275);
DOT 1 (-2200 4225);
DOT 1 (-2200 4175);
DOT 1 (-2200 4125);
DOT 1 (-2200 4075);
DOT 1 (-2200 4025);
DOT 1 (-2200 3975);
DOT 1 (-400 3925);
DOT 1 (-2200 3925);
DOT 1 (-400 3825);
DOT 1 (-400 3875);
DOT 1 (-400 3775);
DOT 1 (-400 3725);
DOT 1 (-400 3675);
DOT 1 (-400 3575);
DOT 1 (-400 3625);
DOT 1 (-400 3525);
DOT 1 (-400 3475);
DOT 1 (-400 3425);
DOT 1 (-400 3325);
DOT 1 (-400 3375);
DOT 1 (-400 3275);
DOT 1 (-400 3225);
DOT 1 (-400 3175);
DOT 1 (-400 3125);
DOT 1 (-400 3075);
DOT 1 (-400 3025);
DOT 1 (-400 2975);
DOT 1 (-400 2925);
DOT 1 (-400 2875);
DOT 1 (-400 2825);
DOT 1 (-400 2775);
DOT 1 (-400 2675);
DOT 1 (-400 2725);
DOT 1 (-400 2625);
DOT 1 (-400 2575);
DOT 1 (-400 2525);
DOT 1 (-400 2475);
DOT 1 (-400 2425);
DOT 1 (-400 2375);
DOT 1 (-400 2325);
DOT 1 (-400 2275);
DOT 1 (-400 2175);
DOT 1 (-400 2125);
DOT 1 (-400 2075);
DOT 1 (-2200 3875);
DOT 1 (-2200 3825);
DOT 1 (-2200 3775);
DOT 1 (-2200 3725);
DOT 1 (-2200 3675);
DOT 1 (-2200 3625);
DOT 1 (-2200 3575);
DOT 1 (-2200 3525);
DOT 1 (-2200 3475);
DOT 1 (-2200 3425);
DOT 1 (-2200 3375);
DOT 1 (-2200 3325);
DOT 1 (-2200 3275);
DOT 1 (-2200 3225);
DOT 1 (-2200 3175);
DOT 1 (-2200 3125);
DOT 1 (-2200 3075);
DOT 1 (-2200 3025);
DOT 1 (-2200 2975);
DOT 1 (-2200 2925);
DOT 1 (-2200 2875);
DOT 1 (-2200 2825);
DOT 1 (-2200 2775);
DOT 1 (-2200 2675);
DOT 1 (-2200 2725);
DOT 1 (-2200 2625);
DOT 1 (-2200 2575);
DOT 1 (-2200 2525);
DOT 1 (-2200 2425);
DOT 1 (-2200 2475);
DOT 1 (-2200 2375);
DOT 1 (-2200 2325);
DOT 1 (-2200 2275);
DOT 1 (-2200 2225);
DOT 1 (-2200 2175);
DOT 1 (-8475 2275);
DOT 1 (-2900 5775);
DOT 1 (-2900 6200);
DOT 1 (-2325 6200);
QUIT
